G04 ================== begin FILE IDENTIFICATION RECORD ==================*
G04 Layout Name:  16368-sb.brd*
G04 Film Name:    16368-sb_X_Y*
G04 File Format:  Gerber RS274X*
G04 File Origin:  Cadence Allegro 16.5-S056*
G04 Origin Date:  Tue Feb 07 09:07:38 2017*
G04 *
G04 Layer:  BOARD GEOMETRY/PANEL_DRAWING*
G04 *
G04 Offset:    (0.00 0.00)*
G04 Mirror:    No*
G04 Mode:      Positive*
G04 Rotation:  0*
G04 FullContactRelief:  No*
G04 UndefLineWidth:     6.00*
G04 ================== end FILE IDENTIFICATION RECORD ====================*
%FSLAX35Y35*MOIN*%
%IR0*IPPOS*OFA0.00000B0.00000*MIA0B0*SFA1.00000B1.00000*%
%ADD10C,.006*%
G75*
%LPD*%
G75*
G54D10*
G01X-217125Y-322874D02*
Y-316574D01*
X-214149D01*
G01X-215245Y-319619D02*
X-217125D01*
G01X-214070Y-86653D02*
X-217204D01*
Y-80353D01*
X-214070D01*
G01X-215324Y-83398D02*
X-217204D01*
G01X-217360Y149567D02*
Y155867D01*
X-215794D01*
X-215167Y155552D01*
X-214697Y155132D01*
X-214305Y154502D01*
X-213992Y153767D01*
X-213914Y152717D01*
X-213992Y151667D01*
X-214305Y150932D01*
X-214697Y150302D01*
X-215167Y149882D01*
X-215794Y149567D01*
X-217360D01*
G01X-213914Y391563D02*
X-214384Y391878D01*
X-214932Y392088D01*
X-215559D01*
X-216264Y391773D01*
X-216812Y391248D01*
X-217204Y390618D01*
X-217517Y389568D01*
X-217595Y388623D01*
X-217439Y387678D01*
X-217204Y387048D01*
X-216734Y386418D01*
X-216185Y385998D01*
X-215637Y385788D01*
X-215089D01*
X-214540Y385998D01*
X-214070Y386313D01*
X-213679Y386733D01*
G01X-215010Y625368D02*
X-214697Y625683D01*
X-214462Y626208D01*
X-214305Y626943D01*
X-214462Y627573D01*
X-214775Y627993D01*
X-215324Y628308D01*
X-217439D01*
Y622008D01*
X-214854D01*
X-214305Y622428D01*
X-213992Y623058D01*
X-213835Y623793D01*
X-213992Y624528D01*
X-214462Y625158D01*
X-215010Y625368D01*
X-217439D01*
G01X-217595Y858229D02*
X-215637Y864529D01*
X-213679Y858229D01*
G01X-214384Y860434D02*
X-216890D01*
G01X-137685Y-392952D02*
Y-386652D01*
X-138625Y-387912D01*
G01Y-392952D02*
X-136745D01*
G01X-137685Y967678D02*
Y973978D01*
X-138625Y972718D01*
G01Y967678D02*
X-136745D01*
G01X-63979Y-2887D02*
X-63388Y-3543D01*
X-62699Y-3937D01*
X-61813Y-4068D01*
X-60927Y-3806D01*
X-60238Y-3281D01*
X-59746Y-2362D01*
X-59647Y-1312D01*
X-59844Y-262D01*
X-60337Y394D01*
X-61026Y919D01*
X-61714Y1050D01*
X-62404Y919D01*
X-63289Y394D01*
X-62994Y3806D01*
X-60337D01*
G01X-53938Y-4330D02*
X-54135Y-4199D01*
Y-3937D01*
X-53938Y-3806D01*
X-53741Y-3937D01*
Y-4199D01*
X-53938Y-4330D01*
G01X-46063Y3806D02*
X-46851Y3544D01*
X-47441Y2887D01*
X-47835Y2100D01*
X-48130Y1050D01*
X-48229Y-131D01*
X-48130Y-1312D01*
X-47835Y-2362D01*
X-47441Y-3150D01*
X-46851Y-3806D01*
X-46063Y-4068D01*
X-45276Y-3806D01*
X-44685Y-3150D01*
X-44291Y-2362D01*
X-43996Y-1312D01*
X-43897Y-131D01*
X-43996Y1050D01*
X-44291Y2100D01*
X-44685Y2887D01*
X-45276Y3544D01*
X-46063Y3806D01*
G01X-38188D02*
X-38976Y3544D01*
X-39566Y2887D01*
X-39960Y2100D01*
X-40255Y1050D01*
X-40354Y-131D01*
X-40255Y-1312D01*
X-39960Y-2362D01*
X-39566Y-3150D01*
X-38976Y-3806D01*
X-38188Y-4068D01*
X-37401Y-3806D01*
X-36810Y-3150D01*
X-36416Y-2362D01*
X-36121Y-1312D01*
X-36022Y-131D01*
X-36121Y1050D01*
X-36416Y2100D01*
X-36810Y2887D01*
X-37401Y3544D01*
X-38188Y3806D01*
G01X-61839Y-15958D02*
X-62627Y-16220D01*
X-63217Y-16877D01*
X-63611Y-17664D01*
X-63906Y-18714D01*
X-64005Y-19895D01*
X-63906Y-21076D01*
X-63611Y-22126D01*
X-63217Y-22914D01*
X-62627Y-23570D01*
X-61839Y-23832D01*
X-61052Y-23570D01*
X-60461Y-22914D01*
X-60067Y-22126D01*
X-59772Y-21076D01*
X-59673Y-19895D01*
X-59772Y-18714D01*
X-60067Y-17664D01*
X-60461Y-16877D01*
X-61052Y-16220D01*
X-61839Y-15958D01*
G01X-53964Y-24094D02*
X-54161Y-23963D01*
Y-23701D01*
X-53964Y-23570D01*
X-53767Y-23701D01*
Y-23963D01*
X-53964Y-24094D01*
G01X-46089Y-15958D02*
X-46877Y-16220D01*
X-47467Y-16877D01*
X-47861Y-17664D01*
X-48156Y-18714D01*
X-48255Y-19895D01*
X-48156Y-21076D01*
X-47861Y-22126D01*
X-47467Y-22914D01*
X-46877Y-23570D01*
X-46089Y-23832D01*
X-45302Y-23570D01*
X-44711Y-22914D01*
X-44317Y-22126D01*
X-44022Y-21076D01*
X-43923Y-19895D01*
X-44022Y-18714D01*
X-44317Y-17664D01*
X-44711Y-16877D01*
X-45302Y-16220D01*
X-46089Y-15958D01*
G01X-38214D02*
X-39002Y-16220D01*
X-39592Y-16877D01*
X-39986Y-17664D01*
X-40281Y-18714D01*
X-40380Y-19895D01*
X-40281Y-21076D01*
X-39986Y-22126D01*
X-39592Y-22914D01*
X-39002Y-23570D01*
X-38214Y-23832D01*
X-37427Y-23570D01*
X-36836Y-22914D01*
X-36442Y-22126D01*
X-36147Y-21076D01*
X-36048Y-19895D01*
X-36147Y-18714D01*
X-36442Y-17664D01*
X-36836Y-16877D01*
X-37427Y-16220D01*
X-38214Y-15958D01*
G01X-64227Y-36614D02*
Y-31614D01*
X-61821D01*
G01X-62707Y-34031D02*
X-64227D01*
G01X-57924Y-33281D02*
Y-36614D01*
G01Y-31947D02*
X-58051Y-31864D01*
Y-31697D01*
X-57924Y-31614D01*
X-57797Y-31697D01*
Y-31864D01*
X-57924Y-31947D01*
G01X-51684Y-31614D02*
Y-36614D01*
G01Y-35864D02*
X-51937Y-36281D01*
X-52317Y-36531D01*
X-52761Y-36614D01*
X-53267Y-36447D01*
X-53647Y-36031D01*
X-53901Y-35531D01*
X-53964Y-34947D01*
X-53901Y-34364D01*
X-53647Y-33864D01*
X-53267Y-33447D01*
X-52761Y-33281D01*
X-52317Y-33364D01*
X-52001Y-33531D01*
X-51684Y-33864D01*
G01X-48801Y-33281D02*
Y-35614D01*
X-48547Y-36197D01*
X-48167Y-36531D01*
X-47724Y-36614D01*
X-47281Y-36531D01*
X-46901Y-36197D01*
X-46647Y-35614D01*
G01Y-36614D02*
Y-33281D01*
G01X-41611Y-33697D02*
X-42054Y-33364D01*
X-42434Y-33281D01*
X-42941Y-33447D01*
X-43321Y-33781D01*
X-43574Y-34364D01*
X-43637Y-34947D01*
X-43574Y-35531D01*
X-43321Y-36031D01*
X-42941Y-36447D01*
X-42434Y-36614D01*
X-41991Y-36447D01*
X-41611Y-36114D01*
G01X-37524Y-33281D02*
Y-36614D01*
G01Y-31947D02*
X-37651Y-31864D01*
Y-31697D01*
X-37524Y-31614D01*
X-37397Y-31697D01*
Y-31864D01*
X-37524Y-31947D01*
G01X-31284Y-36614D02*
Y-33281D01*
G01Y-33864D02*
X-31537Y-33531D01*
X-31917Y-33364D01*
X-32361Y-33281D01*
X-32804Y-33447D01*
X-33184Y-33781D01*
X-33437Y-34281D01*
X-33564Y-34947D01*
X-33437Y-35614D01*
X-33184Y-36114D01*
X-32804Y-36447D01*
X-32361Y-36614D01*
X-31917Y-36531D01*
X-31537Y-36281D01*
X-31284Y-35947D01*
G01X-27324Y-36614D02*
Y-31614D01*
G01X-18771Y-36614D02*
Y-31614D01*
X-17124Y-35781D01*
X-15477Y-31614D01*
Y-36614D01*
G01X-10884D02*
Y-33281D01*
G01Y-33864D02*
X-11137Y-33531D01*
X-11517Y-33364D01*
X-11961Y-33281D01*
X-12404Y-33447D01*
X-12784Y-33781D01*
X-13037Y-34281D01*
X-13164Y-34947D01*
X-13037Y-35614D01*
X-12784Y-36114D01*
X-12404Y-36447D01*
X-11961Y-36614D01*
X-11517Y-36531D01*
X-11137Y-36281D01*
X-10884Y-35947D01*
G01X-7811Y-36614D02*
Y-33281D01*
G01Y-33947D02*
X-7494Y-33614D01*
X-7177Y-33364D01*
X-6734Y-33281D01*
X-6417Y-33364D01*
X-6037Y-33614D01*
G01X-2901Y-36614D02*
Y-31614D01*
G01X-874Y-33281D02*
X-2901Y-35197D01*
G01X-2077Y-34447D02*
X-747Y-36614D01*
G01X7426Y-33281D02*
X9326Y-36614D01*
G01Y-33281D02*
X7426Y-36614D01*
G01X17373Y-32447D02*
X17753Y-31947D01*
X18196Y-31697D01*
X18703Y-31614D01*
X19336Y-31781D01*
X19779Y-32197D01*
X19906Y-32697D01*
X19843Y-33197D01*
X19589Y-33614D01*
X18323Y-34447D01*
X17753Y-35031D01*
X17373Y-35864D01*
X17246Y-36614D01*
X19906D01*
G01X-71055Y73265D02*
X-70465Y74052D01*
X-69776Y74446D01*
X-68988Y74577D01*
X-68004Y74315D01*
X-67315Y73658D01*
X-67118Y72871D01*
X-67216Y72083D01*
X-67610Y71427D01*
X-69579Y70115D01*
X-70465Y69196D01*
X-71055Y67884D01*
X-71252Y66703D01*
X-67118D01*
G01X-63180Y73265D02*
X-62590Y74052D01*
X-61901Y74446D01*
X-61113Y74577D01*
X-60129Y74315D01*
X-59440Y73658D01*
X-59243Y72871D01*
X-59341Y72083D01*
X-59735Y71427D01*
X-61704Y70115D01*
X-62590Y69196D01*
X-63180Y67884D01*
X-63377Y66703D01*
X-59243D01*
G01X-53435Y66441D02*
X-53632Y66572D01*
Y66834D01*
X-53435Y66965D01*
X-53238Y66834D01*
Y66572D01*
X-53435Y66441D01*
G01X-45757Y66703D02*
X-45560Y68409D01*
X-45265Y69852D01*
X-44871Y71165D01*
X-44379Y72608D01*
X-43591Y74577D01*
X-47529D01*
G01X-37685D02*
X-38473Y74315D01*
X-39063Y73658D01*
X-39457Y72871D01*
X-39752Y71821D01*
X-39851Y70640D01*
X-39752Y69459D01*
X-39457Y68409D01*
X-39063Y67621D01*
X-38473Y66965D01*
X-37685Y66703D01*
X-36898Y66965D01*
X-36307Y67621D01*
X-35913Y68409D01*
X-35618Y69459D01*
X-35519Y70640D01*
X-35618Y71821D01*
X-35913Y72871D01*
X-36307Y73658D01*
X-36898Y74315D01*
X-37685Y74577D01*
G01X-71105Y63804D02*
X-70515Y64591D01*
X-69826Y64985D01*
X-69038Y65116D01*
X-68054Y64854D01*
X-67365Y64197D01*
X-67168Y63410D01*
X-67266Y62622D01*
X-67660Y61966D01*
X-69629Y60654D01*
X-70515Y59735D01*
X-71105Y58423D01*
X-71302Y57242D01*
X-67168D01*
G01X-61360Y65116D02*
X-62148Y64854D01*
X-62738Y64197D01*
X-63132Y63410D01*
X-63427Y62360D01*
X-63526Y61179D01*
X-63427Y59998D01*
X-63132Y58948D01*
X-62738Y58160D01*
X-62148Y57504D01*
X-61360Y57242D01*
X-60573Y57504D01*
X-59982Y58160D01*
X-59588Y58948D01*
X-59293Y59998D01*
X-59194Y61179D01*
X-59293Y62360D01*
X-59588Y63410D01*
X-59982Y64197D01*
X-60573Y64854D01*
X-61360Y65116D01*
G01X-53485Y56980D02*
X-53682Y57111D01*
Y57373D01*
X-53485Y57504D01*
X-53288Y57373D01*
Y57111D01*
X-53485Y56980D01*
G01X-45807Y57242D02*
X-45610Y58948D01*
X-45315Y60391D01*
X-44921Y61704D01*
X-44429Y63147D01*
X-43641Y65116D01*
X-47579D01*
G01X-37735D02*
X-38523Y64854D01*
X-39113Y64197D01*
X-39507Y63410D01*
X-39802Y62360D01*
X-39901Y61179D01*
X-39802Y59998D01*
X-39507Y58948D01*
X-39113Y58160D01*
X-38523Y57504D01*
X-37735Y57242D01*
X-36948Y57504D01*
X-36357Y58160D01*
X-35963Y58948D01*
X-35668Y59998D01*
X-35569Y61179D01*
X-35668Y62360D01*
X-35963Y63410D01*
X-36357Y64197D01*
X-36948Y64854D01*
X-37735Y65116D01*
G01X-71984Y198003D02*
X-71393Y197347D01*
X-70704Y196953D01*
X-69818Y196822D01*
X-68932Y197084D01*
X-68243Y197609D01*
X-67751Y198528D01*
X-67652Y199578D01*
X-67849Y200628D01*
X-68342Y201284D01*
X-69031Y201809D01*
X-69719Y201940D01*
X-70409Y201809D01*
X-71294Y201284D01*
X-70999Y204696D01*
X-68342D01*
G01X-63813Y200103D02*
X-63124Y201022D01*
X-62534Y201546D01*
X-61746Y201809D01*
X-61057Y201546D01*
X-60565Y201022D01*
X-60171Y200234D01*
X-60073Y199315D01*
X-60171Y198528D01*
X-60565Y197740D01*
X-61156Y197084D01*
X-61844Y196822D01*
X-62632Y197084D01*
X-63321Y197872D01*
X-63715Y199053D01*
X-63813Y200365D01*
X-63616Y202071D01*
X-63321Y202990D01*
X-62829Y203909D01*
X-62140Y204565D01*
X-61451Y204696D01*
X-60762Y204434D01*
X-60270Y203777D01*
G01X-54068Y196560D02*
X-54265Y196691D01*
Y196953D01*
X-54068Y197084D01*
X-53871Y196953D01*
Y196691D01*
X-54068Y196560D01*
G01X-46193Y196822D02*
Y204696D01*
X-47374Y203121D01*
G01Y196822D02*
X-45012D01*
G01X-38318Y204696D02*
X-39106Y204434D01*
X-39696Y203777D01*
X-40090Y202990D01*
X-40385Y201940D01*
X-40484Y200759D01*
X-40385Y199578D01*
X-40090Y198528D01*
X-39696Y197740D01*
X-39106Y197084D01*
X-38318Y196822D01*
X-37531Y197084D01*
X-36940Y197740D01*
X-36546Y198528D01*
X-36251Y199578D01*
X-36152Y200759D01*
X-36251Y201940D01*
X-36546Y202990D01*
X-36940Y203777D01*
X-37531Y204434D01*
X-38318Y204696D01*
G01X-68054Y138458D02*
Y146332D01*
X-71696Y140689D01*
X-66774D01*
G01X-61360Y146332D02*
X-62148Y146070D01*
X-62738Y145413D01*
X-63132Y144626D01*
X-63427Y143576D01*
X-63526Y142395D01*
X-63427Y141214D01*
X-63132Y140164D01*
X-62738Y139376D01*
X-62148Y138720D01*
X-61360Y138458D01*
X-60573Y138720D01*
X-59982Y139376D01*
X-59588Y140164D01*
X-59293Y141214D01*
X-59194Y142395D01*
X-59293Y143576D01*
X-59588Y144626D01*
X-59982Y145413D01*
X-60573Y146070D01*
X-61360Y146332D01*
G01X-53485Y138196D02*
X-53682Y138327D01*
Y138589D01*
X-53485Y138720D01*
X-53288Y138589D01*
Y138327D01*
X-53485Y138196D01*
G01X-44429Y138458D02*
Y146332D01*
X-48071Y140689D01*
X-43149D01*
G01X-37735Y146332D02*
X-38523Y146070D01*
X-39113Y145413D01*
X-39507Y144626D01*
X-39802Y143576D01*
X-39901Y142395D01*
X-39802Y141214D01*
X-39507Y140164D01*
X-39113Y139376D01*
X-38523Y138720D01*
X-37735Y138458D01*
X-36948Y138720D01*
X-36357Y139376D01*
X-35963Y140164D01*
X-35668Y141214D01*
X-35569Y142395D01*
X-35668Y143576D01*
X-35963Y144626D01*
X-36357Y145413D01*
X-36948Y146070D01*
X-37735Y146332D01*
G01X-71457Y129467D02*
X-70866Y128548D01*
X-70079Y128023D01*
X-69192Y127892D01*
X-68405Y128023D01*
X-67618Y128679D01*
X-67125Y129467D01*
X-67027Y130254D01*
X-67224Y131173D01*
X-67913Y131829D01*
X-68602Y132092D01*
X-69488D01*
G01X-68602D02*
X-68011Y132485D01*
X-67519Y133141D01*
X-67322Y133929D01*
X-67519Y134716D01*
X-68011Y135372D01*
X-68897Y135766D01*
X-69783Y135635D01*
X-70669Y135110D01*
G01X-61416Y127892D02*
X-60727Y128023D01*
X-59940Y128417D01*
X-59447Y129073D01*
X-59250Y129992D01*
X-59447Y130910D01*
X-60038Y131698D01*
X-60924Y132092D01*
X-61908D01*
X-62499Y132354D01*
X-62991Y133010D01*
X-63188Y133929D01*
X-62892Y134847D01*
X-62204Y135504D01*
X-61416Y135766D01*
X-60629Y135504D01*
X-59940Y134847D01*
X-59644Y133929D01*
X-59841Y133010D01*
X-60333Y132354D01*
X-60924Y132092D01*
X-61908D01*
X-62794Y131698D01*
X-63385Y130910D01*
X-63582Y129992D01*
X-63385Y129073D01*
X-62892Y128417D01*
X-62105Y128023D01*
X-61416Y127892D01*
G01X-53541Y127630D02*
X-53738Y127761D01*
Y128023D01*
X-53541Y128154D01*
X-53344Y128023D01*
Y127761D01*
X-53541Y127630D01*
G01X-44485Y127892D02*
Y135766D01*
X-48127Y130123D01*
X-43205D01*
G01X-37791Y135766D02*
X-38579Y135504D01*
X-39169Y134847D01*
X-39563Y134060D01*
X-39858Y133010D01*
X-39957Y131829D01*
X-39858Y130648D01*
X-39563Y129598D01*
X-39169Y128810D01*
X-38579Y128154D01*
X-37791Y127892D01*
X-37004Y128154D01*
X-36413Y128810D01*
X-36019Y129598D01*
X-35724Y130648D01*
X-35625Y131829D01*
X-35724Y133010D01*
X-36019Y134060D01*
X-36413Y134847D01*
X-37004Y135504D01*
X-37791Y135766D01*
G01X-69586Y275443D02*
X-69389Y277149D01*
X-69094Y278592D01*
X-68700Y279905D01*
X-68208Y281348D01*
X-67420Y283317D01*
X-71358D01*
G01X-63680Y276624D02*
X-63089Y275968D01*
X-62400Y275574D01*
X-61514Y275443D01*
X-60628Y275705D01*
X-59939Y276230D01*
X-59447Y277149D01*
X-59348Y278199D01*
X-59545Y279249D01*
X-60038Y279905D01*
X-60727Y280430D01*
X-61415Y280561D01*
X-62105Y280430D01*
X-62990Y279905D01*
X-62695Y283317D01*
X-60038D01*
G01X-53639Y275181D02*
X-53836Y275312D01*
Y275574D01*
X-53639Y275705D01*
X-53442Y275574D01*
Y275312D01*
X-53639Y275181D01*
G01X-45764Y275443D02*
X-45075Y275574D01*
X-44288Y275968D01*
X-43795Y276624D01*
X-43598Y277543D01*
X-43795Y278461D01*
X-44386Y279249D01*
X-45272Y279643D01*
X-46256D01*
X-46847Y279905D01*
X-47339Y280561D01*
X-47536Y281480D01*
X-47240Y282398D01*
X-46552Y283055D01*
X-45764Y283317D01*
X-44977Y283055D01*
X-44288Y282398D01*
X-43992Y281480D01*
X-44189Y280561D01*
X-44681Y279905D01*
X-45272Y279643D01*
X-46256D01*
X-47142Y279249D01*
X-47733Y278461D01*
X-47930Y277543D01*
X-47733Y276624D01*
X-47240Y275968D01*
X-46453Y275574D01*
X-45764Y275443D01*
G01X-37889Y283317D02*
X-38677Y283055D01*
X-39267Y282398D01*
X-39661Y281611D01*
X-39956Y280561D01*
X-40055Y279380D01*
X-39956Y278199D01*
X-39661Y277149D01*
X-39267Y276361D01*
X-38677Y275705D01*
X-37889Y275443D01*
X-37102Y275705D01*
X-36511Y276361D01*
X-36117Y277149D01*
X-35822Y278199D01*
X-35723Y279380D01*
X-35822Y280561D01*
X-36117Y281611D01*
X-36511Y282398D01*
X-37102Y283055D01*
X-37889Y283317D01*
G01X-69586Y266507D02*
X-69389Y268213D01*
X-69094Y269656D01*
X-68700Y270969D01*
X-68208Y272412D01*
X-67420Y274381D01*
X-71358D01*
G01X-63680Y268082D02*
X-63089Y267163D01*
X-62302Y266638D01*
X-61415Y266507D01*
X-60628Y266638D01*
X-59841Y267294D01*
X-59348Y268082D01*
X-59250Y268869D01*
X-59447Y269788D01*
X-60136Y270444D01*
X-60825Y270707D01*
X-61711D01*
G01X-60825D02*
X-60234Y271100D01*
X-59742Y271756D01*
X-59545Y272544D01*
X-59742Y273331D01*
X-60234Y273987D01*
X-61120Y274381D01*
X-62006Y274250D01*
X-62892Y273725D01*
G01X-53639Y266245D02*
X-53836Y266376D01*
Y266638D01*
X-53639Y266769D01*
X-53442Y266638D01*
Y266376D01*
X-53639Y266245D01*
G01X-45764Y266507D02*
X-45075Y266638D01*
X-44288Y267032D01*
X-43795Y267688D01*
X-43598Y268607D01*
X-43795Y269525D01*
X-44386Y270313D01*
X-45272Y270707D01*
X-46256D01*
X-46847Y270969D01*
X-47339Y271625D01*
X-47536Y272544D01*
X-47240Y273462D01*
X-46552Y274119D01*
X-45764Y274381D01*
X-44977Y274119D01*
X-44288Y273462D01*
X-43992Y272544D01*
X-44189Y271625D01*
X-44681Y270969D01*
X-45272Y270707D01*
X-46256D01*
X-47142Y270313D01*
X-47733Y269525D01*
X-47930Y268607D01*
X-47733Y267688D01*
X-47240Y267032D01*
X-46453Y266638D01*
X-45764Y266507D01*
G01X-37889Y274381D02*
X-38677Y274119D01*
X-39267Y273462D01*
X-39661Y272675D01*
X-39956Y271625D01*
X-40055Y270444D01*
X-39956Y269263D01*
X-39661Y268213D01*
X-39267Y267425D01*
X-38677Y266769D01*
X-37889Y266507D01*
X-37102Y266769D01*
X-36511Y267425D01*
X-36117Y268213D01*
X-35822Y269263D01*
X-35723Y270444D01*
X-35822Y271625D01*
X-36117Y272675D01*
X-36511Y273462D01*
X-37102Y274119D01*
X-37889Y274381D01*
G01X-71984Y207510D02*
X-71393Y206854D01*
X-70704Y206460D01*
X-69818Y206329D01*
X-68932Y206591D01*
X-68243Y207116D01*
X-67751Y208035D01*
X-67652Y209085D01*
X-67849Y210135D01*
X-68342Y210791D01*
X-69031Y211316D01*
X-69719Y211447D01*
X-70409Y211316D01*
X-71294Y210791D01*
X-70999Y214203D01*
X-68342D01*
G01X-61943Y206329D02*
X-61254Y206460D01*
X-60467Y206854D01*
X-59974Y207510D01*
X-59777Y208429D01*
X-59974Y209347D01*
X-60565Y210135D01*
X-61451Y210529D01*
X-62435D01*
X-63026Y210791D01*
X-63518Y211447D01*
X-63715Y212366D01*
X-63419Y213284D01*
X-62731Y213941D01*
X-61943Y214203D01*
X-61156Y213941D01*
X-60467Y213284D01*
X-60171Y212366D01*
X-60368Y211447D01*
X-60860Y210791D01*
X-61451Y210529D01*
X-62435D01*
X-63321Y210135D01*
X-63912Y209347D01*
X-64109Y208429D01*
X-63912Y207510D01*
X-63419Y206854D01*
X-62632Y206460D01*
X-61943Y206329D01*
G01X-54068Y206067D02*
X-54265Y206198D01*
Y206460D01*
X-54068Y206591D01*
X-53871Y206460D01*
Y206198D01*
X-54068Y206067D01*
G01X-46193Y206329D02*
Y214203D01*
X-47374Y212628D01*
G01Y206329D02*
X-45012D01*
G01X-38318Y214203D02*
X-39106Y213941D01*
X-39696Y213284D01*
X-40090Y212497D01*
X-40385Y211447D01*
X-40484Y210266D01*
X-40385Y209085D01*
X-40090Y208035D01*
X-39696Y207247D01*
X-39106Y206591D01*
X-38318Y206329D01*
X-37531Y206591D01*
X-36940Y207247D01*
X-36546Y208035D01*
X-36251Y209085D01*
X-36152Y210266D01*
X-36251Y211447D01*
X-36546Y212497D01*
X-36940Y213284D01*
X-37531Y213941D01*
X-38318Y214203D01*
G01X-71062Y345760D02*
X-70373Y345104D01*
X-69586Y344842D01*
X-68798Y345104D01*
X-68109Y345892D01*
X-67617Y347073D01*
X-67420Y348254D01*
Y349698D01*
X-67617Y350879D01*
X-68109Y351929D01*
X-68700Y352454D01*
X-69389Y352716D01*
X-70177Y352454D01*
X-70767Y351929D01*
X-71161Y351141D01*
X-71358Y350091D01*
X-71161Y349173D01*
X-70669Y348254D01*
X-70078Y347729D01*
X-69389Y347598D01*
X-68602Y347860D01*
X-68011Y348516D01*
X-67420Y349698D01*
G01X-63680Y346417D02*
X-63089Y345498D01*
X-62302Y344973D01*
X-61415Y344842D01*
X-60628Y344973D01*
X-59841Y345629D01*
X-59348Y346417D01*
X-59250Y347204D01*
X-59447Y348123D01*
X-60136Y348779D01*
X-60825Y349042D01*
X-61711D01*
G01X-60825D02*
X-60234Y349435D01*
X-59742Y350091D01*
X-59545Y350879D01*
X-59742Y351666D01*
X-60234Y352322D01*
X-61120Y352716D01*
X-62006Y352585D01*
X-62892Y352060D01*
G01X-53639Y344580D02*
X-53836Y344711D01*
Y344973D01*
X-53639Y345104D01*
X-53442Y344973D01*
Y344711D01*
X-53639Y344580D01*
G01X-47930Y346023D02*
X-47339Y345367D01*
X-46650Y344973D01*
X-45764Y344842D01*
X-44878Y345104D01*
X-44189Y345629D01*
X-43697Y346548D01*
X-43598Y347598D01*
X-43795Y348648D01*
X-44288Y349304D01*
X-44977Y349829D01*
X-45665Y349960D01*
X-46355Y349829D01*
X-47240Y349304D01*
X-46945Y352716D01*
X-44288D01*
G01X-37889D02*
X-38677Y352454D01*
X-39267Y351797D01*
X-39661Y351010D01*
X-39956Y349960D01*
X-40055Y348779D01*
X-39956Y347598D01*
X-39661Y346548D01*
X-39267Y345760D01*
X-38677Y345104D01*
X-37889Y344842D01*
X-37102Y345104D01*
X-36511Y345760D01*
X-36117Y346548D01*
X-35822Y347598D01*
X-35723Y348779D01*
X-35822Y349960D01*
X-36117Y351010D01*
X-36511Y351797D01*
X-37102Y352454D01*
X-37889Y352716D01*
G01X-70964Y336756D02*
X-70275Y336100D01*
X-69488Y335838D01*
X-68700Y336100D01*
X-68011Y336888D01*
X-67519Y338069D01*
X-67322Y339250D01*
Y340694D01*
X-67519Y341875D01*
X-68011Y342925D01*
X-68602Y343450D01*
X-69291Y343712D01*
X-70079Y343450D01*
X-70669Y342925D01*
X-71063Y342137D01*
X-71260Y341087D01*
X-71063Y340169D01*
X-70571Y339250D01*
X-69980Y338725D01*
X-69291Y338594D01*
X-68504Y338856D01*
X-67913Y339512D01*
X-67322Y340694D01*
G01X-61416Y335838D02*
Y343712D01*
X-62597Y342137D01*
G01Y335838D02*
X-60235D01*
G01X-53541Y335576D02*
X-53738Y335707D01*
Y335969D01*
X-53541Y336100D01*
X-53344Y335969D01*
Y335707D01*
X-53541Y335576D01*
G01X-47832Y337019D02*
X-47241Y336363D01*
X-46552Y335969D01*
X-45666Y335838D01*
X-44780Y336100D01*
X-44091Y336625D01*
X-43599Y337544D01*
X-43500Y338594D01*
X-43697Y339644D01*
X-44190Y340300D01*
X-44879Y340825D01*
X-45567Y340956D01*
X-46257Y340825D01*
X-47142Y340300D01*
X-46847Y343712D01*
X-44190D01*
G01X-37791D02*
X-38579Y343450D01*
X-39169Y342793D01*
X-39563Y342006D01*
X-39858Y340956D01*
X-39957Y339775D01*
X-39858Y338594D01*
X-39563Y337544D01*
X-39169Y336756D01*
X-38579Y336100D01*
X-37791Y335838D01*
X-37004Y336100D01*
X-36413Y336756D01*
X-36019Y337544D01*
X-35724Y338594D01*
X-35625Y339775D01*
X-35724Y340956D01*
X-36019Y342006D01*
X-36413Y342793D01*
X-37004Y343450D01*
X-37791Y343712D01*
G01X-77288Y415737D02*
Y423611D01*
X-78469Y422036D01*
G01Y415737D02*
X-76107D01*
G01X-69413D02*
Y423611D01*
X-70594Y422036D01*
G01Y415737D02*
X-68232D01*
G01X-61538D02*
Y423611D01*
X-62719Y422036D01*
G01Y415737D02*
X-60357D01*
G01X-53663Y415475D02*
X-53860Y415606D01*
Y415868D01*
X-53663Y415999D01*
X-53466Y415868D01*
Y415606D01*
X-53663Y415475D01*
G01X-47658Y422299D02*
X-47068Y423086D01*
X-46379Y423480D01*
X-45591Y423611D01*
X-44607Y423349D01*
X-43918Y422692D01*
X-43721Y421905D01*
X-43819Y421117D01*
X-44213Y420461D01*
X-46182Y419149D01*
X-47068Y418230D01*
X-47658Y416918D01*
X-47855Y415737D01*
X-43721D01*
G01X-37913Y423611D02*
X-38701Y423349D01*
X-39291Y422692D01*
X-39685Y421905D01*
X-39980Y420855D01*
X-40079Y419674D01*
X-39980Y418493D01*
X-39685Y417443D01*
X-39291Y416655D01*
X-38701Y415999D01*
X-37913Y415737D01*
X-37126Y415999D01*
X-36535Y416655D01*
X-36141Y417443D01*
X-35846Y418493D01*
X-35747Y419674D01*
X-35846Y420855D01*
X-36141Y421905D01*
X-36535Y422692D01*
X-37126Y423349D01*
X-37913Y423611D01*
G01X-77295Y406453D02*
Y414327D01*
X-78476Y412752D01*
G01Y406453D02*
X-76114D01*
G01X-69420Y414327D02*
X-70208Y414065D01*
X-70798Y413408D01*
X-71192Y412621D01*
X-71487Y411571D01*
X-71586Y410390D01*
X-71487Y409209D01*
X-71192Y408159D01*
X-70798Y407371D01*
X-70208Y406715D01*
X-69420Y406453D01*
X-68633Y406715D01*
X-68042Y407371D01*
X-67648Y408159D01*
X-67353Y409209D01*
X-67254Y410390D01*
X-67353Y411571D01*
X-67648Y412621D01*
X-68042Y413408D01*
X-68633Y414065D01*
X-69420Y414327D01*
G01X-63218Y407371D02*
X-62529Y406715D01*
X-61742Y406453D01*
X-60954Y406715D01*
X-60265Y407503D01*
X-59773Y408684D01*
X-59576Y409865D01*
Y411309D01*
X-59773Y412490D01*
X-60265Y413540D01*
X-60856Y414065D01*
X-61545Y414327D01*
X-62333Y414065D01*
X-62923Y413540D01*
X-63317Y412752D01*
X-63514Y411702D01*
X-63317Y410784D01*
X-62825Y409865D01*
X-62234Y409340D01*
X-61545Y409209D01*
X-60758Y409471D01*
X-60167Y410127D01*
X-59576Y411309D01*
G01X-53670Y406191D02*
X-53867Y406322D01*
Y406584D01*
X-53670Y406715D01*
X-53473Y406584D01*
Y406322D01*
X-53670Y406191D01*
G01X-47665Y413015D02*
X-47075Y413802D01*
X-46386Y414196D01*
X-45598Y414327D01*
X-44614Y414065D01*
X-43925Y413408D01*
X-43728Y412621D01*
X-43826Y411833D01*
X-44220Y411177D01*
X-46189Y409865D01*
X-47075Y408946D01*
X-47665Y407634D01*
X-47862Y406453D01*
X-43728D01*
G01X-37920Y414327D02*
X-38708Y414065D01*
X-39298Y413408D01*
X-39692Y412621D01*
X-39987Y411571D01*
X-40086Y410390D01*
X-39987Y409209D01*
X-39692Y408159D01*
X-39298Y407371D01*
X-38708Y406715D01*
X-37920Y406453D01*
X-37133Y406715D01*
X-36542Y407371D01*
X-36148Y408159D01*
X-35853Y409209D01*
X-35754Y410390D01*
X-35853Y411571D01*
X-36148Y412621D01*
X-36542Y413408D01*
X-37133Y414065D01*
X-37920Y414327D01*
G01X-77165Y484806D02*
Y492680D01*
X-78346Y491105D01*
G01Y484806D02*
X-75984D01*
G01X-71160Y491368D02*
X-70570Y492155D01*
X-69881Y492549D01*
X-69093Y492680D01*
X-68109Y492418D01*
X-67420Y491761D01*
X-67223Y490974D01*
X-67321Y490186D01*
X-67715Y489530D01*
X-69684Y488218D01*
X-70570Y487299D01*
X-71160Y485987D01*
X-71357Y484806D01*
X-67223D01*
G01X-61415D02*
X-60726Y484937D01*
X-59939Y485331D01*
X-59446Y485987D01*
X-59249Y486906D01*
X-59446Y487824D01*
X-60037Y488612D01*
X-60923Y489006D01*
X-61907D01*
X-62498Y489268D01*
X-62990Y489924D01*
X-63187Y490843D01*
X-62891Y491761D01*
X-62203Y492418D01*
X-61415Y492680D01*
X-60628Y492418D01*
X-59939Y491761D01*
X-59643Y490843D01*
X-59840Y489924D01*
X-60332Y489268D01*
X-60923Y489006D01*
X-61907D01*
X-62793Y488612D01*
X-63384Y487824D01*
X-63581Y486906D01*
X-63384Y485987D01*
X-62891Y485331D01*
X-62104Y484937D01*
X-61415Y484806D01*
G01X-53540Y484544D02*
X-53737Y484675D01*
Y484937D01*
X-53540Y485068D01*
X-53343Y484937D01*
Y484675D01*
X-53540Y484544D01*
G01X-47338Y485724D02*
X-46649Y485068D01*
X-45862Y484806D01*
X-45074Y485068D01*
X-44385Y485856D01*
X-43893Y487037D01*
X-43696Y488218D01*
Y489662D01*
X-43893Y490843D01*
X-44385Y491893D01*
X-44976Y492418D01*
X-45665Y492680D01*
X-46453Y492418D01*
X-47043Y491893D01*
X-47437Y491105D01*
X-47634Y490055D01*
X-47437Y489137D01*
X-46945Y488218D01*
X-46354Y487693D01*
X-45665Y487562D01*
X-44878Y487824D01*
X-44287Y488480D01*
X-43696Y489662D01*
G01X-37790Y492680D02*
X-38578Y492418D01*
X-39168Y491761D01*
X-39562Y490974D01*
X-39857Y489924D01*
X-39956Y488743D01*
X-39857Y487562D01*
X-39562Y486512D01*
X-39168Y485724D01*
X-38578Y485068D01*
X-37790Y484806D01*
X-37003Y485068D01*
X-36412Y485724D01*
X-36018Y486512D01*
X-35723Y487562D01*
X-35624Y488743D01*
X-35723Y489924D01*
X-36018Y490974D01*
X-36412Y491761D01*
X-37003Y492418D01*
X-37790Y492680D01*
G01X-77165Y475668D02*
Y483542D01*
X-78346Y481967D01*
G01Y475668D02*
X-75984D01*
G01X-71160Y482230D02*
X-70570Y483017D01*
X-69881Y483411D01*
X-69093Y483542D01*
X-68109Y483280D01*
X-67420Y482623D01*
X-67223Y481836D01*
X-67321Y481048D01*
X-67715Y480392D01*
X-69684Y479080D01*
X-70570Y478161D01*
X-71160Y476849D01*
X-71357Y475668D01*
X-67223D01*
G01X-63285Y478949D02*
X-62596Y479868D01*
X-62006Y480392D01*
X-61218Y480655D01*
X-60529Y480392D01*
X-60037Y479868D01*
X-59643Y479080D01*
X-59545Y478161D01*
X-59643Y477374D01*
X-60037Y476586D01*
X-60628Y475930D01*
X-61316Y475668D01*
X-62104Y475930D01*
X-62793Y476718D01*
X-63187Y477899D01*
X-63285Y479211D01*
X-63088Y480917D01*
X-62793Y481836D01*
X-62301Y482755D01*
X-61612Y483411D01*
X-60923Y483542D01*
X-60234Y483280D01*
X-59742Y482623D01*
G01X-53540Y475406D02*
X-53737Y475537D01*
Y475799D01*
X-53540Y475930D01*
X-53343Y475799D01*
Y475537D01*
X-53540Y475406D01*
G01X-47338Y476586D02*
X-46649Y475930D01*
X-45862Y475668D01*
X-45074Y475930D01*
X-44385Y476718D01*
X-43893Y477899D01*
X-43696Y479080D01*
Y480524D01*
X-43893Y481705D01*
X-44385Y482755D01*
X-44976Y483280D01*
X-45665Y483542D01*
X-46453Y483280D01*
X-47043Y482755D01*
X-47437Y481967D01*
X-47634Y480917D01*
X-47437Y479999D01*
X-46945Y479080D01*
X-46354Y478555D01*
X-45665Y478424D01*
X-44878Y478686D01*
X-44287Y479342D01*
X-43696Y480524D01*
G01X-37790Y483542D02*
X-38578Y483280D01*
X-39168Y482623D01*
X-39562Y481836D01*
X-39857Y480786D01*
X-39956Y479605D01*
X-39857Y478424D01*
X-39562Y477374D01*
X-39168Y476586D01*
X-38578Y475930D01*
X-37790Y475668D01*
X-37003Y475930D01*
X-36412Y476586D01*
X-36018Y477374D01*
X-35723Y478424D01*
X-35624Y479605D01*
X-35723Y480786D01*
X-36018Y481836D01*
X-36412Y482623D01*
X-37003Y483280D01*
X-37790Y483542D01*
G01X-77377Y555369D02*
Y563243D01*
X-78558Y561668D01*
G01Y555369D02*
X-76196D01*
G01X-68321D02*
Y563243D01*
X-71963Y557600D01*
X-67041D01*
G01X-63497Y558650D02*
X-62808Y559569D01*
X-62218Y560093D01*
X-61430Y560356D01*
X-60741Y560093D01*
X-60249Y559569D01*
X-59855Y558781D01*
X-59757Y557862D01*
X-59855Y557075D01*
X-60249Y556287D01*
X-60840Y555631D01*
X-61528Y555369D01*
X-62316Y555631D01*
X-63005Y556419D01*
X-63399Y557600D01*
X-63497Y558912D01*
X-63300Y560618D01*
X-63005Y561537D01*
X-62513Y562456D01*
X-61824Y563112D01*
X-61135Y563243D01*
X-60446Y562981D01*
X-59954Y562324D01*
G01X-53752Y555107D02*
X-53949Y555238D01*
Y555500D01*
X-53752Y555631D01*
X-53555Y555500D01*
Y555238D01*
X-53752Y555107D01*
G01X-47747Y558650D02*
X-47058Y559569D01*
X-46468Y560093D01*
X-45680Y560356D01*
X-44991Y560093D01*
X-44499Y559569D01*
X-44105Y558781D01*
X-44007Y557862D01*
X-44105Y557075D01*
X-44499Y556287D01*
X-45090Y555631D01*
X-45778Y555369D01*
X-46566Y555631D01*
X-47255Y556419D01*
X-47649Y557600D01*
X-47747Y558912D01*
X-47550Y560618D01*
X-47255Y561537D01*
X-46763Y562456D01*
X-46074Y563112D01*
X-45385Y563243D01*
X-44696Y562981D01*
X-44204Y562324D01*
G01X-38002Y563243D02*
X-38790Y562981D01*
X-39380Y562324D01*
X-39774Y561537D01*
X-40069Y560487D01*
X-40168Y559306D01*
X-40069Y558125D01*
X-39774Y557075D01*
X-39380Y556287D01*
X-38790Y555631D01*
X-38002Y555369D01*
X-37215Y555631D01*
X-36624Y556287D01*
X-36230Y557075D01*
X-35935Y558125D01*
X-35836Y559306D01*
X-35935Y560487D01*
X-36230Y561537D01*
X-36624Y562324D01*
X-37215Y562981D01*
X-38002Y563243D01*
G01X-77377Y546091D02*
Y553965D01*
X-78558Y552390D01*
G01Y546091D02*
X-76196D01*
G01X-68321D02*
Y553965D01*
X-71963Y548322D01*
X-67041D01*
G01X-60446Y546091D02*
Y553965D01*
X-64088Y548322D01*
X-59166D01*
G01X-53752Y545829D02*
X-53949Y545960D01*
Y546222D01*
X-53752Y546353D01*
X-53555Y546222D01*
Y545960D01*
X-53752Y545829D01*
G01X-47747Y549372D02*
X-47058Y550291D01*
X-46468Y550815D01*
X-45680Y551078D01*
X-44991Y550815D01*
X-44499Y550291D01*
X-44105Y549503D01*
X-44007Y548584D01*
X-44105Y547797D01*
X-44499Y547009D01*
X-45090Y546353D01*
X-45778Y546091D01*
X-46566Y546353D01*
X-47255Y547141D01*
X-47649Y548322D01*
X-47747Y549634D01*
X-47550Y551340D01*
X-47255Y552259D01*
X-46763Y553178D01*
X-46074Y553834D01*
X-45385Y553965D01*
X-44696Y553703D01*
X-44204Y553046D01*
G01X-38002Y553965D02*
X-38790Y553703D01*
X-39380Y553046D01*
X-39774Y552259D01*
X-40069Y551209D01*
X-40168Y550028D01*
X-40069Y548847D01*
X-39774Y547797D01*
X-39380Y547009D01*
X-38790Y546353D01*
X-38002Y546091D01*
X-37215Y546353D01*
X-36624Y547009D01*
X-36230Y547797D01*
X-35935Y548847D01*
X-35836Y550028D01*
X-35935Y551209D01*
X-36230Y552259D01*
X-36624Y553046D01*
X-37215Y553703D01*
X-38002Y553965D01*
G01X-77715Y685014D02*
Y692888D01*
X-78896Y691313D01*
G01Y685014D02*
X-76534D01*
G01X-69840D02*
X-69151Y685145D01*
X-68364Y685539D01*
X-67871Y686195D01*
X-67674Y687114D01*
X-67871Y688032D01*
X-68462Y688820D01*
X-69348Y689214D01*
X-70332D01*
X-70923Y689476D01*
X-71415Y690132D01*
X-71612Y691051D01*
X-71316Y691969D01*
X-70628Y692626D01*
X-69840Y692888D01*
X-69053Y692626D01*
X-68364Y691969D01*
X-68068Y691051D01*
X-68265Y690132D01*
X-68757Y689476D01*
X-69348Y689214D01*
X-70332D01*
X-71218Y688820D01*
X-71809Y688032D01*
X-72006Y687114D01*
X-71809Y686195D01*
X-71316Y685539D01*
X-70529Y685145D01*
X-69840Y685014D01*
G01X-61965Y692888D02*
X-62753Y692626D01*
X-63343Y691969D01*
X-63737Y691182D01*
X-64032Y690132D01*
X-64131Y688951D01*
X-64032Y687770D01*
X-63737Y686720D01*
X-63343Y685932D01*
X-62753Y685276D01*
X-61965Y685014D01*
X-61178Y685276D01*
X-60587Y685932D01*
X-60193Y686720D01*
X-59898Y687770D01*
X-59799Y688951D01*
X-59898Y690132D01*
X-60193Y691182D01*
X-60587Y691969D01*
X-61178Y692626D01*
X-61965Y692888D01*
G01X-54090Y684752D02*
X-54287Y684883D01*
Y685145D01*
X-54090Y685276D01*
X-53893Y685145D01*
Y684883D01*
X-54090Y684752D01*
G01X-46215Y692888D02*
X-47003Y692626D01*
X-47593Y691969D01*
X-47987Y691182D01*
X-48282Y690132D01*
X-48381Y688951D01*
X-48282Y687770D01*
X-47987Y686720D01*
X-47593Y685932D01*
X-47003Y685276D01*
X-46215Y685014D01*
X-45428Y685276D01*
X-44837Y685932D01*
X-44443Y686720D01*
X-44148Y687770D01*
X-44049Y688951D01*
X-44148Y690132D01*
X-44443Y691182D01*
X-44837Y691969D01*
X-45428Y692626D01*
X-46215Y692888D01*
G01X-38340D02*
X-39128Y692626D01*
X-39718Y691969D01*
X-40112Y691182D01*
X-40407Y690132D01*
X-40506Y688951D01*
X-40407Y687770D01*
X-40112Y686720D01*
X-39718Y685932D01*
X-39128Y685276D01*
X-38340Y685014D01*
X-37553Y685276D01*
X-36962Y685932D01*
X-36568Y686720D01*
X-36273Y687770D01*
X-36174Y688951D01*
X-36273Y690132D01*
X-36568Y691182D01*
X-36962Y691969D01*
X-37553Y692626D01*
X-38340Y692888D01*
G01X-77377Y625829D02*
Y633703D01*
X-78558Y632128D01*
G01Y625829D02*
X-76196D01*
G01X-71372Y629110D02*
X-70683Y630029D01*
X-70093Y630553D01*
X-69305Y630816D01*
X-68616Y630553D01*
X-68124Y630029D01*
X-67730Y629241D01*
X-67632Y628322D01*
X-67730Y627535D01*
X-68124Y626747D01*
X-68715Y626091D01*
X-69403Y625829D01*
X-70191Y626091D01*
X-70880Y626879D01*
X-71274Y628060D01*
X-71372Y629372D01*
X-71175Y631078D01*
X-70880Y631997D01*
X-70388Y632916D01*
X-69699Y633572D01*
X-69010Y633703D01*
X-68321Y633441D01*
X-67829Y632784D01*
G01X-60446Y625829D02*
Y633703D01*
X-64088Y628060D01*
X-59166D01*
G01X-53752Y625567D02*
X-53949Y625698D01*
Y625960D01*
X-53752Y626091D01*
X-53555Y625960D01*
Y625698D01*
X-53752Y625567D01*
G01X-48043Y627404D02*
X-47452Y626485D01*
X-46665Y625960D01*
X-45778Y625829D01*
X-44991Y625960D01*
X-44204Y626616D01*
X-43711Y627404D01*
X-43613Y628191D01*
X-43810Y629110D01*
X-44499Y629766D01*
X-45188Y630029D01*
X-46074D01*
G01X-45188D02*
X-44597Y630422D01*
X-44105Y631078D01*
X-43908Y631866D01*
X-44105Y632653D01*
X-44597Y633309D01*
X-45483Y633703D01*
X-46369Y633572D01*
X-47255Y633047D01*
G01X-38002Y633703D02*
X-38790Y633441D01*
X-39380Y632784D01*
X-39774Y631997D01*
X-40069Y630947D01*
X-40168Y629766D01*
X-40069Y628585D01*
X-39774Y627535D01*
X-39380Y626747D01*
X-38790Y626091D01*
X-38002Y625829D01*
X-37215Y626091D01*
X-36624Y626747D01*
X-36230Y627535D01*
X-35935Y628585D01*
X-35836Y629766D01*
X-35935Y630947D01*
X-36230Y631997D01*
X-36624Y632784D01*
X-37215Y633441D01*
X-38002Y633703D01*
G01X-77377Y615776D02*
Y623650D01*
X-78558Y622075D01*
G01Y615776D02*
X-76196D01*
G01X-71372Y619057D02*
X-70683Y619976D01*
X-70093Y620500D01*
X-69305Y620763D01*
X-68616Y620500D01*
X-68124Y619976D01*
X-67730Y619188D01*
X-67632Y618269D01*
X-67730Y617482D01*
X-68124Y616694D01*
X-68715Y616038D01*
X-69403Y615776D01*
X-70191Y616038D01*
X-70880Y616826D01*
X-71274Y618007D01*
X-71372Y619319D01*
X-71175Y621025D01*
X-70880Y621944D01*
X-70388Y622863D01*
X-69699Y623519D01*
X-69010Y623650D01*
X-68321Y623388D01*
X-67829Y622731D01*
G01X-63497Y622338D02*
X-62907Y623125D01*
X-62218Y623519D01*
X-61430Y623650D01*
X-60446Y623388D01*
X-59757Y622731D01*
X-59560Y621944D01*
X-59658Y621156D01*
X-60052Y620500D01*
X-62021Y619188D01*
X-62907Y618269D01*
X-63497Y616957D01*
X-63694Y615776D01*
X-59560D01*
G01X-53752Y615514D02*
X-53949Y615645D01*
Y615907D01*
X-53752Y616038D01*
X-53555Y615907D01*
Y615645D01*
X-53752Y615514D01*
G01X-48043Y617351D02*
X-47452Y616432D01*
X-46665Y615907D01*
X-45778Y615776D01*
X-44991Y615907D01*
X-44204Y616563D01*
X-43711Y617351D01*
X-43613Y618138D01*
X-43810Y619057D01*
X-44499Y619713D01*
X-45188Y619976D01*
X-46074D01*
G01X-45188D02*
X-44597Y620369D01*
X-44105Y621025D01*
X-43908Y621813D01*
X-44105Y622600D01*
X-44597Y623256D01*
X-45483Y623650D01*
X-46369Y623519D01*
X-47255Y622994D01*
G01X-38002Y623650D02*
X-38790Y623388D01*
X-39380Y622731D01*
X-39774Y621944D01*
X-40069Y620894D01*
X-40168Y619713D01*
X-40069Y618532D01*
X-39774Y617482D01*
X-39380Y616694D01*
X-38790Y616038D01*
X-38002Y615776D01*
X-37215Y616038D01*
X-36624Y616694D01*
X-36230Y617482D01*
X-35935Y618532D01*
X-35836Y619713D01*
X-35935Y620894D01*
X-36230Y621944D01*
X-36624Y622731D01*
X-37215Y623388D01*
X-38002Y623650D01*
G01X-3937Y722466D02*
X-3675Y721678D01*
X-3018Y721088D01*
X-2231Y720694D01*
X-1181Y720399D01*
X0Y720300D01*
X1181Y720399D01*
X2231Y720694D01*
X3019Y721088D01*
X3675Y721678D01*
X3937Y722466D01*
X3675Y723253D01*
X3019Y723844D01*
X2231Y724238D01*
X1181Y724533D01*
X0Y724632D01*
X-1181Y724533D01*
X-2231Y724238D01*
X-3018Y723844D01*
X-3675Y723253D01*
X-3937Y722466D01*
G01X4199Y730341D02*
X4068Y730144D01*
X3806D01*
X3675Y730341D01*
X3806Y730538D01*
X4068D01*
X4199Y730341D01*
G01X-3937Y738216D02*
X-3675Y737428D01*
X-3018Y736838D01*
X-2231Y736444D01*
X-1181Y736149D01*
X0Y736050D01*
X1181Y736149D01*
X2231Y736444D01*
X3019Y736838D01*
X3675Y737428D01*
X3937Y738216D01*
X3675Y739003D01*
X3019Y739594D01*
X2231Y739988D01*
X1181Y740283D01*
X0Y740382D01*
X-1181Y740283D01*
X-2231Y739988D01*
X-3018Y739594D01*
X-3675Y739003D01*
X-3937Y738216D01*
G01Y746091D02*
X-3675Y745303D01*
X-3018Y744713D01*
X-2231Y744319D01*
X-1181Y744024D01*
X0Y743925D01*
X1181Y744024D01*
X2231Y744319D01*
X3019Y744713D01*
X3675Y745303D01*
X3937Y746091D01*
X3675Y746878D01*
X3019Y747469D01*
X2231Y747863D01*
X1181Y748158D01*
X0Y748257D01*
X-1181Y748158D01*
X-2231Y747863D01*
X-3018Y747469D01*
X-3675Y746878D01*
X-3937Y746091D01*
G01X44055Y-387702D02*
X44525Y-387072D01*
X45073Y-386757D01*
X45700Y-386652D01*
X46483Y-386862D01*
X47031Y-387387D01*
X47188Y-388017D01*
X47110Y-388647D01*
X46796Y-389172D01*
X45230Y-390222D01*
X44525Y-390957D01*
X44055Y-392007D01*
X43898Y-392952D01*
X47188D01*
G01X81094Y32349D02*
Y24475D01*
G01X78830Y32349D02*
X83358D01*
G01X81094Y102034D02*
Y94160D01*
G01X78830Y102034D02*
X83358D01*
G01X81094Y171719D02*
Y163845D01*
G01X78830Y171719D02*
X83358D01*
G01X81094Y241404D02*
Y233530D01*
G01X78830Y241404D02*
X83358D01*
G01X81094Y311089D02*
Y303215D01*
G01X78830Y311089D02*
X83358D01*
G01X81094Y450459D02*
Y442585D01*
G01X78830Y450459D02*
X83358D01*
G01X81094Y380774D02*
Y372900D01*
G01X78830Y380774D02*
X83358D01*
G01X81094Y520144D02*
Y512270D01*
G01X78830Y520144D02*
X83358D01*
G01X81094Y589829D02*
Y581955D01*
G01X78830Y589829D02*
X83358D01*
G01X81094Y659514D02*
Y651640D01*
G01X78830Y659514D02*
X83358D01*
G01X44055Y972928D02*
X44525Y973558D01*
X45073Y973873D01*
X45700Y973978D01*
X46483Y973768D01*
X47031Y973243D01*
X47188Y972613D01*
X47110Y971983D01*
X46796Y971458D01*
X45230Y970408D01*
X44525Y969673D01*
X44055Y968623D01*
X43898Y967678D01*
X47188D01*
G01X188977Y723647D02*
X181103D01*
X186746Y720005D01*
Y724927D01*
G01X188977Y730144D02*
X187271Y730341D01*
X185828Y730636D01*
X184515Y731030D01*
X183072Y731522D01*
X181103Y732310D01*
Y728372D01*
G01X189239Y738216D02*
X189108Y738019D01*
X188846D01*
X188715Y738216D01*
X188846Y738413D01*
X189108D01*
X189239Y738216D01*
G01X181103Y746091D02*
X181365Y745303D01*
X182022Y744713D01*
X182809Y744319D01*
X183859Y744024D01*
X185040Y743925D01*
X186221Y744024D01*
X187271Y744319D01*
X188059Y744713D01*
X188715Y745303D01*
X188977Y746091D01*
X188715Y746878D01*
X188059Y747469D01*
X187271Y747863D01*
X186221Y748158D01*
X185040Y748257D01*
X183859Y748158D01*
X182809Y747863D01*
X182022Y747469D01*
X181365Y746878D01*
X181103Y746091D01*
G01Y753966D02*
X181365Y753178D01*
X182022Y752588D01*
X182809Y752194D01*
X183859Y751899D01*
X185040Y751800D01*
X186221Y751899D01*
X187271Y752194D01*
X188059Y752588D01*
X188715Y753178D01*
X188977Y753966D01*
X188715Y754753D01*
X188059Y755344D01*
X187271Y755738D01*
X186221Y756033D01*
X185040Y756132D01*
X183859Y756033D01*
X182809Y755738D01*
X182022Y755344D01*
X181365Y754753D01*
X181103Y753966D01*
G01X179517Y723647D02*
X171643D01*
X177286Y720005D01*
Y724927D01*
G01X178336Y728175D02*
X178992Y728766D01*
X179386Y729455D01*
X179517Y730341D01*
X179255Y731227D01*
X178730Y731916D01*
X177811Y732408D01*
X176761Y732507D01*
X175711Y732310D01*
X175055Y731817D01*
X174530Y731128D01*
X174399Y730440D01*
X174530Y729750D01*
X175055Y728865D01*
X171643Y729160D01*
Y731817D01*
G01X179779Y738216D02*
X179648Y738019D01*
X179386D01*
X179255Y738216D01*
X179386Y738413D01*
X179648D01*
X179779Y738216D01*
G01X171643Y746091D02*
X171905Y745303D01*
X172562Y744713D01*
X173349Y744319D01*
X174399Y744024D01*
X175580Y743925D01*
X176761Y744024D01*
X177811Y744319D01*
X178599Y744713D01*
X179255Y745303D01*
X179517Y746091D01*
X179255Y746878D01*
X178599Y747469D01*
X177811Y747863D01*
X176761Y748158D01*
X175580Y748257D01*
X174399Y748158D01*
X173349Y747863D01*
X172562Y747469D01*
X171905Y746878D01*
X171643Y746091D01*
G01Y753966D02*
X171905Y753178D01*
X172562Y752588D01*
X173349Y752194D01*
X174399Y751899D01*
X175580Y751800D01*
X176761Y751899D01*
X177811Y752194D01*
X178599Y752588D01*
X179255Y753178D01*
X179517Y753966D01*
X179255Y754753D01*
X178599Y755344D01*
X177811Y755738D01*
X176761Y756033D01*
X175580Y756132D01*
X174399Y756033D01*
X173349Y755738D01*
X172562Y755344D01*
X171905Y754753D01*
X171643Y753966D01*
G01X217048Y-391692D02*
X217518Y-392427D01*
X218144Y-392847D01*
X218849Y-392952D01*
X219476Y-392847D01*
X220103Y-392322D01*
X220494Y-391692D01*
X220573Y-391062D01*
X220416Y-390327D01*
X219868Y-389802D01*
X219319Y-389592D01*
X218614D01*
G01X219319D02*
X219789Y-389277D01*
X220181Y-388752D01*
X220338Y-388122D01*
X220181Y-387492D01*
X219789Y-386967D01*
X219084Y-386652D01*
X218379Y-386757D01*
X217674Y-387177D01*
G01X266133Y32349D02*
Y24475D01*
G01X263869Y32349D02*
X268397D01*
G01X266133Y102034D02*
Y94160D01*
G01X263869Y102034D02*
X268397D01*
G01X266133Y171719D02*
Y163845D01*
G01X263869Y171719D02*
X268397D01*
G01X266133Y241404D02*
Y233530D01*
G01X263869Y241404D02*
X268397D01*
G01X266133Y311089D02*
Y303215D01*
G01X263869Y311089D02*
X268397D01*
G01X266133Y450459D02*
Y442585D01*
G01X263869Y450459D02*
X268397D01*
G01X266133Y380774D02*
Y372900D01*
G01X263869Y380774D02*
X268397D01*
G01X266133Y520144D02*
Y512270D01*
G01X263869Y520144D02*
X268397D01*
G01X266133Y589829D02*
Y581955D01*
G01X263869Y589829D02*
X268397D01*
G01X266133Y659514D02*
Y651640D01*
G01X263869Y659514D02*
X268397D01*
G01X217048Y968938D02*
X217518Y968203D01*
X218144Y967783D01*
X218849Y967678D01*
X219476Y967783D01*
X220103Y968308D01*
X220494Y968938D01*
X220573Y969568D01*
X220416Y970303D01*
X219868Y970828D01*
X219319Y971038D01*
X218614D01*
G01X219319D02*
X219789Y971353D01*
X220181Y971878D01*
X220338Y972508D01*
X220181Y973138D01*
X219789Y973663D01*
X219084Y973978D01*
X218379Y973873D01*
X217674Y973453D01*
G01X362844Y720793D02*
X363500Y721482D01*
X363762Y722269D01*
X363500Y723057D01*
X362712Y723746D01*
X361531Y724238D01*
X360350Y724435D01*
X358906D01*
X357725Y724238D01*
X356675Y723746D01*
X356150Y723155D01*
X355888Y722466D01*
X356150Y721678D01*
X356675Y721088D01*
X357463Y720694D01*
X358513Y720497D01*
X359431Y720694D01*
X360350Y721186D01*
X360875Y721777D01*
X361006Y722466D01*
X360744Y723253D01*
X360088Y723844D01*
X358906Y724435D01*
G01X357200Y728471D02*
X356413Y729061D01*
X356019Y729750D01*
X355888Y730538D01*
X356150Y731522D01*
X356807Y732211D01*
X357594Y732408D01*
X358382Y732310D01*
X359038Y731916D01*
X360350Y729947D01*
X361269Y729061D01*
X362581Y728471D01*
X363762Y728274D01*
Y732408D01*
G01X364024Y738216D02*
X363893Y738019D01*
X363631D01*
X363500Y738216D01*
X363631Y738413D01*
X363893D01*
X364024Y738216D01*
G01X355888Y746091D02*
X356150Y745303D01*
X356807Y744713D01*
X357594Y744319D01*
X358644Y744024D01*
X359825Y743925D01*
X361006Y744024D01*
X362056Y744319D01*
X362844Y744713D01*
X363500Y745303D01*
X363762Y746091D01*
X363500Y746878D01*
X362844Y747469D01*
X362056Y747863D01*
X361006Y748158D01*
X359825Y748257D01*
X358644Y748158D01*
X357594Y747863D01*
X356807Y747469D01*
X356150Y746878D01*
X355888Y746091D01*
G01Y753966D02*
X356150Y753178D01*
X356807Y752588D01*
X357594Y752194D01*
X358644Y751899D01*
X359825Y751800D01*
X361006Y751899D01*
X362056Y752194D01*
X362844Y752588D01*
X363500Y753178D01*
X363762Y753966D01*
X363500Y754753D01*
X362844Y755344D01*
X362056Y755738D01*
X361006Y756033D01*
X359825Y756132D01*
X358644Y756033D01*
X357594Y755738D01*
X356807Y755344D01*
X356150Y754753D01*
X355888Y753966D01*
G01X392940Y-392952D02*
Y-386652D01*
X390042Y-391167D01*
X393958D01*
G01X373098Y720793D02*
X373754Y721482D01*
X374016Y722269D01*
X373754Y723057D01*
X372966Y723746D01*
X371785Y724238D01*
X370604Y724435D01*
X369160D01*
X367979Y724238D01*
X366929Y723746D01*
X366404Y723155D01*
X366142Y722466D01*
X366404Y721678D01*
X366929Y721088D01*
X367717Y720694D01*
X368767Y720497D01*
X369685Y720694D01*
X370604Y721186D01*
X371129Y721777D01*
X371260Y722466D01*
X370998Y723253D01*
X370342Y723844D01*
X369160Y724435D01*
G01X374016Y731522D02*
X366142D01*
X371785Y727880D01*
Y732802D01*
G01X374278Y738216D02*
X374147Y738019D01*
X373885D01*
X373754Y738216D01*
X373885Y738413D01*
X374147D01*
X374278Y738216D01*
G01X366142Y746091D02*
X366404Y745303D01*
X367061Y744713D01*
X367848Y744319D01*
X368898Y744024D01*
X370079Y743925D01*
X371260Y744024D01*
X372310Y744319D01*
X373098Y744713D01*
X373754Y745303D01*
X374016Y746091D01*
X373754Y746878D01*
X373098Y747469D01*
X372310Y747863D01*
X371260Y748158D01*
X370079Y748257D01*
X368898Y748158D01*
X367848Y747863D01*
X367061Y747469D01*
X366404Y746878D01*
X366142Y746091D01*
G01Y753966D02*
X366404Y753178D01*
X367061Y752588D01*
X367848Y752194D01*
X368898Y751899D01*
X370079Y751800D01*
X371260Y751899D01*
X372310Y752194D01*
X373098Y752588D01*
X373754Y753178D01*
X374016Y753966D01*
X373754Y754753D01*
X373098Y755344D01*
X372310Y755738D01*
X371260Y756033D01*
X370079Y756132D01*
X368898Y756033D01*
X367848Y755738D01*
X367061Y755344D01*
X366404Y754753D01*
X366142Y753966D01*
G01X392940Y967678D02*
Y973978D01*
X390042Y969463D01*
X393958D01*
G01X451172Y32349D02*
Y24475D01*
G01X448908Y32349D02*
X453436D01*
G01X451172Y102034D02*
Y94160D01*
G01X448908Y102034D02*
X453436D01*
G01X451172Y171719D02*
Y163845D01*
G01X448908Y171719D02*
X453436D01*
G01X451172Y241404D02*
Y233530D01*
G01X448908Y241404D02*
X453436D01*
G01X451172Y311089D02*
Y303215D01*
G01X448908Y311089D02*
X453436D01*
G01X451172Y450459D02*
Y442585D01*
G01X448908Y450459D02*
X453436D01*
G01X451172Y380774D02*
Y372900D01*
G01X448908Y380774D02*
X453436D01*
G01X451172Y520144D02*
Y512270D01*
G01X448908Y520144D02*
X453436D01*
G01X451172Y589829D02*
Y581955D01*
G01X448908Y589829D02*
X453436D01*
G01X451172Y659514D02*
Y651640D01*
G01X448908Y659514D02*
X453436D01*
G01X563505Y-392007D02*
X563975Y-392532D01*
X564523Y-392847D01*
X565228Y-392952D01*
X565933Y-392742D01*
X566481Y-392322D01*
X566873Y-391587D01*
X566951Y-390747D01*
X566795Y-389907D01*
X566403Y-389382D01*
X565855Y-388962D01*
X565306Y-388857D01*
X564758Y-388962D01*
X564053Y-389382D01*
X564288Y-386652D01*
X566403D01*
G01X544564Y36633D02*
X545351Y35977D01*
X546237Y35583D01*
X547025D01*
X547812Y35977D01*
X548403Y36633D01*
X548698Y37552D01*
X548501Y38470D01*
X548009Y39257D01*
X547123Y39783D01*
X545942Y40045D01*
X545253Y40570D01*
X544958Y41488D01*
X545155Y42407D01*
X545647Y43063D01*
X546336Y43457D01*
X547025D01*
X547714Y43195D01*
X548304Y42538D01*
G01X553030Y39126D02*
X556179D01*
X555884Y40045D01*
X555392Y40570D01*
X554703Y40832D01*
X554014Y40701D01*
X553423Y40307D01*
X553030Y39389D01*
X552833Y38601D01*
Y37814D01*
X553030Y37026D01*
X553522Y36239D01*
X554112Y35714D01*
X554801Y35583D01*
X555490Y35845D01*
X556179Y36633D01*
G01X561003Y35583D02*
Y40832D01*
G01Y39783D02*
X561495Y40307D01*
X561987Y40701D01*
X562676Y40832D01*
X563168Y40701D01*
X563759Y40307D01*
G01X570256Y40832D02*
Y35583D01*
G01Y42932D02*
X570059Y43063D01*
Y43326D01*
X570256Y43457D01*
X570453Y43326D01*
Y43063D01*
X570256Y42932D01*
G01X576655Y39126D02*
X579804D01*
X579509Y40045D01*
X579017Y40570D01*
X578328Y40832D01*
X577639Y40701D01*
X577048Y40307D01*
X576655Y39389D01*
X576458Y38601D01*
Y37814D01*
X576655Y37026D01*
X577147Y36239D01*
X577737Y35714D01*
X578426Y35583D01*
X579115Y35845D01*
X579804Y36633D01*
G01X584530Y36501D02*
X585022Y35977D01*
X585711Y35583D01*
X586301D01*
X586892Y35845D01*
X587286Y36239D01*
X587482Y36764D01*
X587384Y37552D01*
X586990Y37945D01*
X585218Y38732D01*
X584825Y39651D01*
X585022Y40307D01*
X585415Y40701D01*
X586006Y40832D01*
X586597Y40701D01*
X587187Y40307D01*
G01X600083Y35583D02*
Y40832D01*
G01Y39520D02*
X600476Y40176D01*
X601067Y40701D01*
X601855Y40832D01*
X602543Y40701D01*
X603134Y40176D01*
X603429Y39257D01*
Y35583D01*
G01X607958Y40832D02*
Y37158D01*
X608351Y36239D01*
X608942Y35714D01*
X609631Y35583D01*
X610320Y35714D01*
X610911Y36239D01*
X611304Y37158D01*
G01Y35583D02*
Y40832D01*
G01X614553Y35583D02*
Y40832D01*
G01Y39389D02*
X614848Y40045D01*
X615340Y40570D01*
X616030Y40832D01*
X616718Y40570D01*
X617211Y40045D01*
X617506Y39389D01*
Y35583D01*
G01Y39389D02*
X617801Y40045D01*
X618293Y40570D01*
X618982Y40832D01*
X619672Y40570D01*
X620164Y40045D01*
X620459Y39257D01*
Y35583D01*
G01X623609D02*
Y43457D01*
G01Y39520D02*
X624101Y40307D01*
X624692Y40701D01*
X625282Y40832D01*
X626168Y40570D01*
X626759Y40045D01*
X627153Y39126D01*
Y38076D01*
X626956Y37026D01*
X626562Y36239D01*
X625873Y35714D01*
X625282Y35583D01*
X624692Y35714D01*
X624101Y36108D01*
X623609Y36764D01*
G01X631780Y39126D02*
X634929D01*
X634634Y40045D01*
X634142Y40570D01*
X633453Y40832D01*
X632764Y40701D01*
X632173Y40307D01*
X631780Y39389D01*
X631583Y38601D01*
Y37814D01*
X631780Y37026D01*
X632272Y36239D01*
X632862Y35714D01*
X633551Y35583D01*
X634240Y35845D01*
X634929Y36633D01*
G01X639753Y35583D02*
Y40832D01*
G01Y39783D02*
X640245Y40307D01*
X640737Y40701D01*
X641426Y40832D01*
X641918Y40701D01*
X642509Y40307D01*
G01X658653Y35583D02*
Y40832D01*
G01Y39914D02*
X658259Y40439D01*
X657668Y40701D01*
X656980Y40832D01*
X656290Y40570D01*
X655700Y40045D01*
X655306Y39257D01*
X655109Y38208D01*
X655306Y37158D01*
X655700Y36370D01*
X656290Y35845D01*
X656980Y35583D01*
X657668Y35714D01*
X658259Y36108D01*
X658653Y36633D01*
G01X663083Y35583D02*
Y40832D01*
G01Y39520D02*
X663476Y40176D01*
X664067Y40701D01*
X664855Y40832D01*
X665543Y40701D01*
X666134Y40176D01*
X666429Y39257D01*
Y35583D01*
G01X674403Y43457D02*
Y35583D01*
G01Y36764D02*
X674009Y36108D01*
X673418Y35714D01*
X672730Y35583D01*
X671942Y35845D01*
X671351Y36501D01*
X670958Y37289D01*
X670859Y38208D01*
X670958Y39126D01*
X671351Y39914D01*
X671942Y40570D01*
X672730Y40832D01*
X673418Y40701D01*
X673911Y40439D01*
X674403Y39914D01*
G01X687003Y35583D02*
Y40832D01*
G01Y39783D02*
X687495Y40307D01*
X687987Y40701D01*
X688676Y40832D01*
X689168Y40701D01*
X689759Y40307D01*
G01X694780Y39126D02*
X697929D01*
X697634Y40045D01*
X697142Y40570D01*
X696453Y40832D01*
X695764Y40701D01*
X695173Y40307D01*
X694780Y39389D01*
X694583Y38601D01*
Y37814D01*
X694780Y37026D01*
X695272Y36239D01*
X695862Y35714D01*
X696551Y35583D01*
X697240Y35845D01*
X697929Y36633D01*
G01X703540Y35583D02*
Y42276D01*
X703737Y42932D01*
X704131Y43326D01*
X704722Y43457D01*
X705312Y43195D01*
X705607Y42538D01*
G01X704426Y40307D02*
X702458D01*
G01X710530Y39126D02*
X713679D01*
X713384Y40045D01*
X712892Y40570D01*
X712203Y40832D01*
X711514Y40701D01*
X710923Y40307D01*
X710530Y39389D01*
X710333Y38601D01*
Y37814D01*
X710530Y37026D01*
X711022Y36239D01*
X711612Y35714D01*
X712301Y35583D01*
X712990Y35845D01*
X713679Y36633D01*
G01X718503Y35583D02*
Y40832D01*
G01Y39783D02*
X718995Y40307D01*
X719487Y40701D01*
X720176Y40832D01*
X720668Y40701D01*
X721259Y40307D01*
G01X726280Y39126D02*
X729429D01*
X729134Y40045D01*
X728642Y40570D01*
X727953Y40832D01*
X727264Y40701D01*
X726673Y40307D01*
X726280Y39389D01*
X726083Y38601D01*
Y37814D01*
X726280Y37026D01*
X726772Y36239D01*
X727362Y35714D01*
X728051Y35583D01*
X728740Y35845D01*
X729429Y36633D01*
G01X733958Y35583D02*
Y40832D01*
G01Y39520D02*
X734351Y40176D01*
X734942Y40701D01*
X735730Y40832D01*
X736418Y40701D01*
X737009Y40176D01*
X737304Y39257D01*
Y35583D01*
G01X745081Y40176D02*
X744392Y40701D01*
X743801Y40832D01*
X743014Y40570D01*
X742423Y40045D01*
X742030Y39126D01*
X741931Y38208D01*
X742030Y37289D01*
X742423Y36501D01*
X743014Y35845D01*
X743801Y35583D01*
X744490Y35845D01*
X745081Y36370D01*
G01X749905Y39126D02*
X753054D01*
X752759Y40045D01*
X752267Y40570D01*
X751578Y40832D01*
X750889Y40701D01*
X750298Y40307D01*
X749905Y39389D01*
X749708Y38601D01*
Y37814D01*
X749905Y37026D01*
X750397Y36239D01*
X750987Y35714D01*
X751676Y35583D01*
X752365Y35845D01*
X753054Y36633D01*
G01X767131Y35583D02*
X766540Y35714D01*
X765950Y36239D01*
X765556Y37158D01*
X765359Y38208D01*
X765556Y39257D01*
X765950Y40176D01*
X766540Y40701D01*
X767131Y40832D01*
X767722Y40701D01*
X768312Y40176D01*
X768706Y39257D01*
X768804Y38208D01*
X768706Y37158D01*
X768312Y36239D01*
X767722Y35714D01*
X767131Y35583D01*
G01X773333D02*
Y40832D01*
G01Y39520D02*
X773726Y40176D01*
X774317Y40701D01*
X775105Y40832D01*
X775793Y40701D01*
X776384Y40176D01*
X776679Y39257D01*
Y35583D01*
G01X782881D02*
Y43457D01*
G01X788689Y33221D02*
X789280Y32958D01*
X790067Y33221D01*
X790559Y33746D01*
X790953Y34402D01*
X791543Y36501D01*
X792823Y40832D01*
G01X789673D02*
X791543Y36501D01*
G01X798631Y35321D02*
X798434Y35452D01*
Y35714D01*
X798631Y35845D01*
X798828Y35714D01*
Y35452D01*
X798631Y35321D01*
G01X551181Y722466D02*
X543307D01*
X544882Y721285D01*
G01X551181D02*
Y723647D01*
G01X549606Y728175D02*
X550525Y728766D01*
X551050Y729553D01*
X551181Y730440D01*
X551050Y731227D01*
X550394Y732014D01*
X549606Y732507D01*
X548819Y732605D01*
X547900Y732408D01*
X547244Y731719D01*
X546981Y731030D01*
Y730144D01*
G01Y731030D02*
X546588Y731621D01*
X545932Y732113D01*
X545144Y732310D01*
X544357Y732113D01*
X543701Y731621D01*
X543307Y730735D01*
X543438Y729849D01*
X543963Y728963D01*
G01X550263Y736543D02*
X550919Y737232D01*
X551181Y738019D01*
X550919Y738807D01*
X550131Y739496D01*
X548950Y739988D01*
X547769Y740185D01*
X546325D01*
X545144Y739988D01*
X544094Y739496D01*
X543569Y738905D01*
X543307Y738216D01*
X543569Y737428D01*
X544094Y736838D01*
X544882Y736444D01*
X545932Y736247D01*
X546850Y736444D01*
X547769Y736936D01*
X548294Y737527D01*
X548425Y738216D01*
X548163Y739003D01*
X547507Y739594D01*
X546325Y740185D01*
G01X551443Y746091D02*
X551312Y745894D01*
X551050D01*
X550919Y746091D01*
X551050Y746288D01*
X551312D01*
X551443Y746091D01*
G01X543307Y753966D02*
X543569Y753178D01*
X544226Y752588D01*
X545013Y752194D01*
X546063Y751899D01*
X547244Y751800D01*
X548425Y751899D01*
X549475Y752194D01*
X550263Y752588D01*
X550919Y753178D01*
X551181Y753966D01*
X550919Y754753D01*
X550263Y755344D01*
X549475Y755738D01*
X548425Y756033D01*
X547244Y756132D01*
X546063Y756033D01*
X545013Y755738D01*
X544226Y755344D01*
X543569Y754753D01*
X543307Y753966D01*
G01Y761841D02*
X543569Y761053D01*
X544226Y760463D01*
X545013Y760069D01*
X546063Y759774D01*
X547244Y759675D01*
X548425Y759774D01*
X549475Y760069D01*
X550263Y760463D01*
X550919Y761053D01*
X551181Y761841D01*
X550919Y762628D01*
X550263Y763219D01*
X549475Y763613D01*
X548425Y763908D01*
X547244Y764007D01*
X546063Y763908D01*
X545013Y763613D01*
X544226Y763219D01*
X543569Y762628D01*
X543307Y761841D01*
G01X563505Y968623D02*
X563975Y968098D01*
X564523Y967783D01*
X565228Y967678D01*
X565933Y967888D01*
X566481Y968308D01*
X566873Y969043D01*
X566951Y969883D01*
X566795Y970723D01*
X566403Y971248D01*
X565855Y971668D01*
X565306Y971773D01*
X564758Y971668D01*
X564053Y971248D01*
X564288Y973978D01*
X566403D01*
G01X736968Y-390327D02*
X737516Y-389592D01*
X737986Y-389172D01*
X738613Y-388962D01*
X739161Y-389172D01*
X739553Y-389592D01*
X739866Y-390222D01*
X739944Y-390957D01*
X739866Y-391587D01*
X739553Y-392217D01*
X739083Y-392742D01*
X738534Y-392952D01*
X737908Y-392742D01*
X737359Y-392112D01*
X737046Y-391167D01*
X736968Y-390117D01*
X737124Y-388752D01*
X737359Y-388017D01*
X737751Y-387282D01*
X738299Y-386757D01*
X738848Y-386652D01*
X739396Y-386862D01*
X739788Y-387387D01*
G01X736968Y970303D02*
X737516Y971038D01*
X737986Y971458D01*
X738613Y971668D01*
X739161Y971458D01*
X739553Y971038D01*
X739866Y970408D01*
X739944Y969673D01*
X739866Y969043D01*
X739553Y968413D01*
X739083Y967888D01*
X738534Y967678D01*
X737908Y967888D01*
X737359Y968518D01*
X737046Y969463D01*
X736968Y970513D01*
X737124Y971878D01*
X737359Y972613D01*
X737751Y973348D01*
X738299Y973873D01*
X738848Y973978D01*
X739396Y973768D01*
X739788Y973243D01*
G01X798762Y-277503D02*
X797183Y-276450D01*
X795340Y-275748D01*
X793234D01*
X790865Y-276801D01*
X789023Y-278556D01*
X787706Y-280662D01*
X786653Y-284172D01*
X786390Y-287331D01*
X786917Y-290489D01*
X787706Y-292595D01*
X789286Y-294702D01*
X791129Y-296105D01*
X792971Y-296807D01*
X794813D01*
X796656Y-296105D01*
X798236Y-295052D01*
X799552Y-293649D01*
G01X810345Y-296807D02*
Y-282768D01*
G01Y-285575D02*
X811661Y-284172D01*
X812977Y-283119D01*
X814820Y-282768D01*
X816136Y-283119D01*
X817715Y-284172D01*
G01X831141Y-287331D02*
X839564D01*
X838774Y-284874D01*
X837458Y-283470D01*
X835616Y-282768D01*
X833773Y-283119D01*
X832193Y-284172D01*
X831141Y-286629D01*
X830614Y-288735D01*
Y-290840D01*
X831141Y-292946D01*
X832457Y-295052D01*
X834036Y-296456D01*
X835879Y-296807D01*
X837721Y-296105D01*
X839564Y-294000D01*
G01X860886Y-296807D02*
Y-282768D01*
G01Y-285224D02*
X859833Y-283821D01*
X858254Y-283119D01*
X856411Y-282768D01*
X854569Y-283470D01*
X852989Y-284874D01*
X851936Y-286980D01*
X851410Y-289788D01*
X851936Y-292595D01*
X852989Y-294702D01*
X854569Y-296105D01*
X856411Y-296807D01*
X858254Y-296456D01*
X859833Y-295403D01*
X860886Y-294000D01*
G01X877207Y-275748D02*
Y-296807D01*
G01X873522Y-282768D02*
X880892D01*
G01X894318Y-287331D02*
X902741D01*
X901951Y-284874D01*
X900635Y-283470D01*
X898793Y-282768D01*
X896950Y-283119D01*
X895370Y-284172D01*
X894318Y-286629D01*
X893791Y-288735D01*
Y-290840D01*
X894318Y-292946D01*
X895634Y-295052D01*
X897213Y-296456D01*
X899056Y-296807D01*
X900898Y-296105D01*
X902741Y-294000D01*
G01X924063Y-275748D02*
Y-296807D01*
G01Y-293649D02*
X923010Y-295403D01*
X921431Y-296456D01*
X919588Y-296807D01*
X917483Y-296105D01*
X915903Y-294351D01*
X914850Y-292245D01*
X914587Y-289788D01*
X914850Y-287331D01*
X915903Y-285224D01*
X917483Y-283470D01*
X919588Y-282768D01*
X921431Y-283119D01*
X922747Y-283821D01*
X924063Y-285224D01*
G01X783688Y-226840D02*
X790269Y-247899D01*
X796850Y-226840D01*
G01X807380Y-238423D02*
X815803D01*
X815013Y-235966D01*
X813697Y-234562D01*
X811855Y-233860D01*
X810012Y-234211D01*
X808432Y-235264D01*
X807380Y-237721D01*
X806853Y-239827D01*
Y-241932D01*
X807380Y-244038D01*
X808696Y-246144D01*
X810275Y-247548D01*
X812118Y-247899D01*
X813960Y-247197D01*
X815803Y-245092D01*
G01X828702Y-247899D02*
Y-233860D01*
G01Y-236667D02*
X830018Y-235264D01*
X831334Y-234211D01*
X833177Y-233860D01*
X834493Y-234211D01*
X836072Y-235264D01*
G01X849498Y-245443D02*
X850814Y-246846D01*
X852656Y-247899D01*
X854236D01*
X855815Y-247197D01*
X856868Y-246144D01*
X857394Y-244741D01*
X857131Y-242634D01*
X856078Y-241581D01*
X851340Y-239476D01*
X850287Y-237018D01*
X850814Y-235264D01*
X851867Y-234211D01*
X853446Y-233860D01*
X855025Y-234211D01*
X856605Y-235264D01*
G01X874505Y-233860D02*
Y-247899D01*
G01Y-228244D02*
X873978Y-227893D01*
Y-227191D01*
X874505Y-226840D01*
X875032Y-227191D01*
Y-227893D01*
X874505Y-228244D01*
G01X895564Y-247899D02*
X893985Y-247548D01*
X892405Y-246144D01*
X891352Y-243687D01*
X890826Y-240880D01*
X891352Y-238072D01*
X892405Y-235615D01*
X893985Y-234211D01*
X895564Y-233860D01*
X897143Y-234211D01*
X898723Y-235615D01*
X899776Y-238072D01*
X900039Y-240880D01*
X899776Y-243687D01*
X898723Y-246144D01*
X897143Y-247548D01*
X895564Y-247899D01*
G01X912148D02*
Y-233860D01*
G01Y-237370D02*
X913201Y-235615D01*
X914781Y-234211D01*
X916886Y-233860D01*
X918729Y-234211D01*
X920308Y-235615D01*
X921098Y-238072D01*
Y-247899D01*
G01X796188Y-159672D02*
Y-131092D01*
X805476Y-154909D01*
X814765Y-131092D01*
Y-159672D01*
G01X834056D02*
X831913Y-159196D01*
X829769Y-157291D01*
X828340Y-153956D01*
X827626Y-150146D01*
X828340Y-146335D01*
X829769Y-143000D01*
X831913Y-141095D01*
X834056Y-140619D01*
X836200Y-141095D01*
X838344Y-143000D01*
X839772Y-146335D01*
X840130Y-150146D01*
X839772Y-153956D01*
X838344Y-157291D01*
X836200Y-159196D01*
X834056Y-159672D01*
G01X869067Y-131092D02*
Y-159672D01*
G01Y-155386D02*
X867638Y-157767D01*
X865494Y-159196D01*
X862994Y-159672D01*
X860136Y-158720D01*
X857992Y-156338D01*
X856563Y-153480D01*
X856206Y-150146D01*
X856563Y-146811D01*
X857992Y-143953D01*
X860136Y-141572D01*
X862994Y-140619D01*
X865494Y-141095D01*
X867281Y-142048D01*
X869067Y-143953D01*
G01X885858Y-146811D02*
X897290D01*
X896218Y-143477D01*
X894432Y-141572D01*
X891931Y-140619D01*
X889430Y-141095D01*
X887287Y-142524D01*
X885858Y-145859D01*
X885143Y-148717D01*
Y-151574D01*
X885858Y-154433D01*
X887644Y-157291D01*
X889787Y-159196D01*
X892288Y-159672D01*
X894789Y-158720D01*
X897290Y-155862D01*
G01X919796Y-159672D02*
Y-131092D01*
G01X787706Y-203885D02*
Y-182826D01*
X794024D01*
X796130Y-183879D01*
X797709Y-186336D01*
X798236Y-189144D01*
X797709Y-191952D01*
X796393Y-194058D01*
X794024Y-195111D01*
X787706D01*
G01X819821Y-184581D02*
X818242Y-183528D01*
X816399Y-182826D01*
X814293D01*
X811924Y-183879D01*
X810082Y-185634D01*
X808765Y-187740D01*
X807712Y-191250D01*
X807449Y-194409D01*
X807976Y-197567D01*
X808765Y-199673D01*
X810345Y-201780D01*
X812188Y-203183D01*
X814030Y-203885D01*
X815872D01*
X817715Y-203183D01*
X819295Y-202130D01*
X820611Y-200727D01*
G01X837195Y-192653D02*
X838248Y-191601D01*
X839037Y-189846D01*
X839564Y-187388D01*
X839037Y-185283D01*
X837985Y-183879D01*
X836142Y-182826D01*
X829035D01*
Y-203885D01*
X837721D01*
X839564Y-202481D01*
X840617Y-200375D01*
X841143Y-197918D01*
X840617Y-195462D01*
X839037Y-193356D01*
X837195Y-192653D01*
X829035D01*
G01X871153Y-203885D02*
Y-182826D01*
X883261Y-203885D01*
Y-182826D01*
G01X898266Y-203885D02*
X896687Y-203534D01*
X895107Y-202130D01*
X894054Y-199673D01*
X893528Y-196866D01*
X894054Y-194058D01*
X895107Y-191601D01*
X896687Y-190197D01*
X898266Y-189846D01*
X899845Y-190197D01*
X901425Y-191601D01*
X902478Y-194058D01*
X902741Y-196866D01*
X902478Y-199673D01*
X901425Y-202130D01*
X899845Y-203534D01*
X898266Y-203885D01*
G01X919325Y-204587D02*
X918798Y-204236D01*
Y-203534D01*
X919325Y-203183D01*
X919852Y-203534D01*
Y-204236D01*
X919325Y-204587D01*
G01X911528Y-392952D02*
X911685Y-391587D01*
X911920Y-390432D01*
X912233Y-389382D01*
X912625Y-388227D01*
X913252Y-386652D01*
X910118D01*
G01X911528Y967678D02*
X911685Y969043D01*
X911920Y970198D01*
X912233Y971248D01*
X912625Y972403D01*
X913252Y973978D01*
X910118D01*
G01X965753Y-319497D02*
X971675Y-353341D01*
X978444Y-319497D01*
X985213Y-353341D01*
X991136Y-319497D01*
G01X1012288Y-330779D02*
Y-353341D01*
G01Y-321754D02*
X1011442Y-321190D01*
Y-320061D01*
X1012288Y-319497D01*
X1013135Y-320061D01*
Y-321190D01*
X1012288Y-321754D01*
G01X1039787Y-349393D02*
X1041902Y-351649D01*
X1044863Y-353341D01*
X1047402D01*
X1049940Y-352213D01*
X1051632Y-350521D01*
X1052478Y-348265D01*
X1052055Y-344880D01*
X1050363Y-343188D01*
X1042748Y-339804D01*
X1041056Y-335855D01*
X1041902Y-333035D01*
X1043594Y-331343D01*
X1046132Y-330779D01*
X1048671Y-331343D01*
X1051209Y-333035D01*
G01X1079976Y-319497D02*
Y-353341D01*
G01X1074054Y-330779D02*
X1085899D01*
G01X1107898Y-353341D02*
Y-330779D01*
G01Y-335291D02*
X1110013Y-333035D01*
X1112128Y-331343D01*
X1115090Y-330779D01*
X1117205Y-331343D01*
X1119743Y-333035D01*
G01X1147664Y-353341D02*
X1145126Y-352777D01*
X1142588Y-350521D01*
X1140895Y-346573D01*
X1140049Y-342060D01*
X1140895Y-337547D01*
X1142588Y-333599D01*
X1145126Y-331343D01*
X1147664Y-330779D01*
X1150203Y-331343D01*
X1152741Y-333599D01*
X1154433Y-337547D01*
X1154857Y-342060D01*
X1154433Y-346573D01*
X1152741Y-350521D01*
X1150203Y-352777D01*
X1147664Y-353341D01*
G01X1174316D02*
Y-330779D01*
G01Y-336420D02*
X1176009Y-333599D01*
X1178547Y-331343D01*
X1181932Y-330779D01*
X1184893Y-331343D01*
X1187431Y-333599D01*
X1188701Y-337547D01*
Y-353341D01*
G01X1258504Y-322318D02*
X1255965Y-320625D01*
X1253004Y-319497D01*
X1249620D01*
X1245812Y-321190D01*
X1242851Y-324010D01*
X1240735Y-327394D01*
X1239043Y-333035D01*
X1238620Y-338111D01*
X1239466Y-343188D01*
X1240735Y-346573D01*
X1243274Y-349957D01*
X1246235Y-352213D01*
X1249196Y-353341D01*
X1252158D01*
X1255119Y-352213D01*
X1257658Y-350521D01*
X1259773Y-348265D01*
G01X1283040Y-353341D02*
X1280502Y-352777D01*
X1277964Y-350521D01*
X1276271Y-346573D01*
X1275425Y-342060D01*
X1276271Y-337547D01*
X1277964Y-333599D01*
X1280502Y-331343D01*
X1283040Y-330779D01*
X1285579Y-331343D01*
X1288117Y-333599D01*
X1289809Y-337547D01*
X1290233Y-342060D01*
X1289809Y-346573D01*
X1288117Y-350521D01*
X1285579Y-352777D01*
X1283040Y-353341D01*
G01X1310962D02*
Y-330779D01*
G01Y-335291D02*
X1313077Y-333035D01*
X1315192Y-331343D01*
X1318154Y-330779D01*
X1320269Y-331343D01*
X1322807Y-333035D01*
G01X1343113Y-364622D02*
Y-330779D01*
G01Y-335855D02*
X1345229Y-333035D01*
X1347344Y-331343D01*
X1350728Y-330779D01*
X1353690Y-331343D01*
X1356651Y-334163D01*
X1357921Y-338111D01*
X1358344Y-342060D01*
X1357921Y-346009D01*
X1356651Y-349957D01*
X1354113Y-352213D01*
X1350728Y-353341D01*
X1347767Y-352777D01*
X1344806Y-351085D01*
X1343113Y-348829D01*
G01X1384572Y-353341D02*
X1382034Y-352777D01*
X1379496Y-350521D01*
X1377803Y-346573D01*
X1376957Y-342060D01*
X1377803Y-337547D01*
X1379496Y-333599D01*
X1382034Y-331343D01*
X1384572Y-330779D01*
X1387111Y-331343D01*
X1389649Y-333599D01*
X1391341Y-337547D01*
X1391765Y-342060D01*
X1391341Y-346573D01*
X1389649Y-350521D01*
X1387111Y-352777D01*
X1384572Y-353341D01*
G01X1412494D02*
Y-330779D01*
G01Y-335291D02*
X1414609Y-333035D01*
X1416724Y-331343D01*
X1419686Y-330779D01*
X1421801Y-331343D01*
X1424339Y-333035D01*
G01X1459876Y-353341D02*
Y-330779D01*
G01Y-334727D02*
X1458183Y-332471D01*
X1455645Y-331343D01*
X1452684Y-330779D01*
X1449722Y-331907D01*
X1447184Y-334163D01*
X1445491Y-337547D01*
X1444645Y-342060D01*
X1445491Y-346573D01*
X1447184Y-349957D01*
X1449722Y-352213D01*
X1452684Y-353341D01*
X1455645Y-352777D01*
X1458183Y-351085D01*
X1459876Y-348829D01*
G01X1486104Y-319497D02*
Y-353341D01*
G01X1480182Y-330779D02*
X1492027D01*
G01X1519948D02*
Y-353341D01*
G01Y-321754D02*
X1519102Y-321190D01*
Y-320061D01*
X1519948Y-319497D01*
X1520795Y-320061D01*
Y-321190D01*
X1519948Y-321754D01*
G01X1553792Y-353341D02*
X1551254Y-352777D01*
X1548716Y-350521D01*
X1547023Y-346573D01*
X1546177Y-342060D01*
X1547023Y-337547D01*
X1548716Y-333599D01*
X1551254Y-331343D01*
X1553792Y-330779D01*
X1556331Y-331343D01*
X1558869Y-333599D01*
X1560561Y-337547D01*
X1560985Y-342060D01*
X1560561Y-346573D01*
X1558869Y-350521D01*
X1556331Y-352777D01*
X1553792Y-353341D01*
G01X1580444D02*
Y-330779D01*
G01Y-336420D02*
X1582137Y-333599D01*
X1584675Y-331343D01*
X1588060Y-330779D01*
X1591021Y-331343D01*
X1593559Y-333599D01*
X1594829Y-337547D01*
Y-353341D01*
G01X988844Y-273773D02*
X995425Y-294832D01*
X1002006Y-273773D01*
G01X1016484Y-280793D02*
Y-294832D01*
G01Y-275177D02*
X1015957Y-274826D01*
Y-274124D01*
X1016484Y-273773D01*
X1017011Y-274124D01*
Y-274826D01*
X1016484Y-275177D01*
G01X1037543Y-294832D02*
Y-273773D01*
G01X1054654Y-285356D02*
X1063077D01*
X1062287Y-282899D01*
X1060971Y-281495D01*
X1059129Y-280793D01*
X1057286Y-281144D01*
X1055706Y-282197D01*
X1054654Y-284654D01*
X1054127Y-286760D01*
Y-288865D01*
X1054654Y-290971D01*
X1055970Y-293077D01*
X1057549Y-294481D01*
X1059392Y-294832D01*
X1061234Y-294130D01*
X1063077Y-292025D01*
G01X1084399Y-294832D02*
Y-280793D01*
G01Y-283249D02*
X1083346Y-281846D01*
X1081767Y-281144D01*
X1079924Y-280793D01*
X1078082Y-281495D01*
X1076502Y-282899D01*
X1075449Y-285005D01*
X1074923Y-287813D01*
X1075449Y-290620D01*
X1076502Y-292727D01*
X1078082Y-294130D01*
X1079924Y-294832D01*
X1081767Y-294481D01*
X1083346Y-293428D01*
X1084399Y-292025D01*
G01X1096245Y-294832D02*
Y-280793D01*
G01Y-284303D02*
X1097298Y-282548D01*
X1098878Y-281144D01*
X1100983Y-280793D01*
X1102826Y-281144D01*
X1104405Y-282548D01*
X1105195Y-285005D01*
Y-294832D01*
G01X1009674Y-249985D02*
X1011780Y-251739D01*
X1014149Y-252792D01*
X1016255D01*
X1018361Y-251739D01*
X1019940Y-249985D01*
X1020730Y-247527D01*
X1020204Y-245071D01*
X1018887Y-242965D01*
X1016518Y-241560D01*
X1013360Y-240859D01*
X1011517Y-239455D01*
X1010727Y-236998D01*
X1011254Y-234541D01*
X1012570Y-232786D01*
X1014412Y-231733D01*
X1016255D01*
X1018098Y-232435D01*
X1019677Y-234190D01*
G01X1038367Y-241560D02*
X1039420Y-240508D01*
X1040209Y-238753D01*
X1040736Y-236295D01*
X1040209Y-234190D01*
X1039157Y-232786D01*
X1037314Y-231733D01*
X1030207D01*
Y-252792D01*
X1038893D01*
X1040736Y-251388D01*
X1041789Y-249282D01*
X1042315Y-246825D01*
X1041789Y-244369D01*
X1040209Y-242263D01*
X1038367Y-241560D01*
X1030207D01*
G01X984743Y-127024D02*
Y-155966D01*
X999213D01*
G01X1023813Y-140530D02*
X1025260Y-139083D01*
X1026345Y-136672D01*
X1027069Y-133294D01*
X1026345Y-130401D01*
X1024899Y-128472D01*
X1022366Y-127024D01*
X1012598D01*
Y-155966D01*
X1024537D01*
X1027069Y-154037D01*
X1028516Y-151142D01*
X1029240Y-147766D01*
X1028516Y-144390D01*
X1026345Y-141495D01*
X1023813Y-140530D01*
X1012598D01*
G01X1057819Y-129436D02*
X1055648Y-127989D01*
X1053116Y-127024D01*
X1050222D01*
X1046965Y-128472D01*
X1044434Y-130883D01*
X1042625Y-133777D01*
X1041177Y-138601D01*
X1040815Y-142942D01*
X1041539Y-147283D01*
X1042625Y-150178D01*
X1044795Y-153072D01*
X1047328Y-155001D01*
X1049860Y-155966D01*
X1052392D01*
X1054925Y-155001D01*
X1057095Y-153555D01*
X1058905Y-151626D01*
G01X1100507Y-127024D02*
Y-155966D01*
X1114977D01*
G01X1143918D02*
X1129448D01*
Y-127024D01*
X1143918D01*
G01X1138130Y-141012D02*
X1129448D01*
G01X1157665Y-155966D02*
Y-127024D01*
X1164900D01*
X1167794Y-128472D01*
X1169965Y-130401D01*
X1171774Y-133294D01*
X1173221Y-136672D01*
X1173583Y-141495D01*
X1173221Y-146319D01*
X1171774Y-149696D01*
X1169965Y-152590D01*
X1167794Y-154519D01*
X1164900Y-155966D01*
X1157665D01*
G01X1229294Y-139083D02*
X1226762Y-137154D01*
X1224591Y-136672D01*
X1221697Y-137636D01*
X1219526Y-139566D01*
X1218080Y-142942D01*
X1217717Y-146319D01*
X1218080Y-149696D01*
X1219526Y-152590D01*
X1221697Y-155001D01*
X1224591Y-155966D01*
X1227124Y-155001D01*
X1229294Y-153072D01*
G01X1258959Y-155966D02*
Y-136672D01*
G01Y-140048D02*
X1257512Y-138119D01*
X1255341Y-137154D01*
X1252809Y-136672D01*
X1250277Y-137636D01*
X1248106Y-139566D01*
X1246658Y-142460D01*
X1245935Y-146319D01*
X1246658Y-150178D01*
X1248106Y-153072D01*
X1250277Y-155001D01*
X1252809Y-155966D01*
X1255341Y-155484D01*
X1257512Y-154037D01*
X1258959Y-152108D01*
G01X1276323Y-155966D02*
Y-136672D01*
G01Y-140530D02*
X1278132Y-138601D01*
X1279941Y-137154D01*
X1282473Y-136672D01*
X1284282Y-137154D01*
X1286453Y-138601D01*
G01X1316841Y-127024D02*
Y-155966D01*
G01Y-151626D02*
X1315394Y-154037D01*
X1313223Y-155484D01*
X1310691Y-155966D01*
X1307797Y-155001D01*
X1305626Y-152590D01*
X1304179Y-149696D01*
X1303817Y-146319D01*
X1304179Y-142942D01*
X1305626Y-140048D01*
X1307797Y-137636D01*
X1310691Y-136672D01*
X1313223Y-137154D01*
X1315032Y-138119D01*
X1316841Y-140048D01*
G01X1001173Y-201910D02*
Y-180851D01*
X998014Y-185063D01*
G01Y-201910D02*
X1004331D01*
G01X1017230Y-193136D02*
X1019073Y-190678D01*
X1020653Y-189275D01*
X1022759Y-188573D01*
X1024601Y-189275D01*
X1025917Y-190678D01*
X1026970Y-192784D01*
X1027234Y-195241D01*
X1026970Y-197348D01*
X1025917Y-199454D01*
X1024338Y-201208D01*
X1022495Y-201910D01*
X1020390Y-201208D01*
X1018547Y-199103D01*
X1017494Y-195943D01*
X1017230Y-192434D01*
X1017757Y-187871D01*
X1018547Y-185413D01*
X1019863Y-182957D01*
X1021705Y-181202D01*
X1023548Y-180851D01*
X1025391Y-181553D01*
X1026707Y-183308D01*
G01X1037500Y-197698D02*
X1039079Y-200155D01*
X1041185Y-201559D01*
X1043554Y-201910D01*
X1045660Y-201559D01*
X1047766Y-199805D01*
X1049082Y-197698D01*
X1049345Y-195592D01*
X1048819Y-193136D01*
X1046976Y-191381D01*
X1045133Y-190678D01*
X1042764D01*
G01X1045133D02*
X1046713Y-189626D01*
X1048029Y-187871D01*
X1048556Y-185765D01*
X1048029Y-183659D01*
X1046713Y-181904D01*
X1044344Y-180851D01*
X1041975Y-181202D01*
X1039606Y-182606D01*
G01X1059348Y-193136D02*
X1061191Y-190678D01*
X1062771Y-189275D01*
X1064877Y-188573D01*
X1066719Y-189275D01*
X1068035Y-190678D01*
X1069088Y-192784D01*
X1069352Y-195241D01*
X1069088Y-197348D01*
X1068035Y-199454D01*
X1066456Y-201208D01*
X1064613Y-201910D01*
X1062508Y-201208D01*
X1060665Y-199103D01*
X1059612Y-195943D01*
X1059348Y-192434D01*
X1059875Y-187871D01*
X1060665Y-185413D01*
X1061981Y-182957D01*
X1063823Y-181202D01*
X1065666Y-180851D01*
X1067509Y-181553D01*
X1068825Y-183308D01*
G01X1085409Y-201910D02*
X1087251Y-201559D01*
X1089357Y-200506D01*
X1090674Y-198752D01*
X1091200Y-196294D01*
X1090674Y-193838D01*
X1089094Y-191732D01*
X1086725Y-190678D01*
X1084093D01*
X1082513Y-189977D01*
X1081197Y-188222D01*
X1080671Y-185765D01*
X1081461Y-183308D01*
X1083303Y-181553D01*
X1085409Y-180851D01*
X1087515Y-181553D01*
X1089357Y-183308D01*
X1090147Y-185765D01*
X1089621Y-188222D01*
X1088305Y-189977D01*
X1086725Y-190678D01*
X1084093D01*
X1081724Y-191732D01*
X1080144Y-193838D01*
X1079618Y-196294D01*
X1080144Y-198752D01*
X1081461Y-200506D01*
X1083567Y-201559D01*
X1085409Y-201910D01*
G01X1084913Y-392952D02*
X1085461Y-392847D01*
X1086088Y-392532D01*
X1086480Y-392007D01*
X1086636Y-391272D01*
X1086480Y-390537D01*
X1086010Y-389907D01*
X1085305Y-389592D01*
X1084521D01*
X1084051Y-389382D01*
X1083660Y-388857D01*
X1083503Y-388122D01*
X1083738Y-387387D01*
X1084286Y-386862D01*
X1084913Y-386652D01*
X1085540Y-386862D01*
X1086088Y-387387D01*
X1086323Y-388122D01*
X1086166Y-388857D01*
X1085775Y-389382D01*
X1085305Y-389592D01*
X1084521D01*
X1083816Y-389907D01*
X1083346Y-390537D01*
X1083190Y-391272D01*
X1083346Y-392007D01*
X1083738Y-392532D01*
X1084365Y-392847D01*
X1084913Y-392952D01*
G01X1033387Y239065D02*
X1038766Y247993D01*
X1035071Y249352D01*
X1033387Y239065D01*
G01X1084913Y967678D02*
X1085461Y967783D01*
X1086088Y968098D01*
X1086480Y968623D01*
X1086636Y969358D01*
X1086480Y970093D01*
X1086010Y970723D01*
X1085305Y971038D01*
X1084521D01*
X1084051Y971248D01*
X1083660Y971773D01*
X1083503Y972508D01*
X1083738Y973243D01*
X1084286Y973768D01*
X1084913Y973978D01*
X1085540Y973768D01*
X1086088Y973243D01*
X1086323Y972508D01*
X1086166Y971773D01*
X1085775Y971248D01*
X1085305Y971038D01*
X1084521D01*
X1083816Y970723D01*
X1083346Y970093D01*
X1083190Y969358D01*
X1083346Y968623D01*
X1083738Y968098D01*
X1084365Y967783D01*
X1084913Y967678D01*
G01X1256810Y-392217D02*
X1257359Y-392742D01*
X1257985Y-392952D01*
X1258612Y-392742D01*
X1259160Y-392112D01*
X1259552Y-391167D01*
X1259709Y-390222D01*
Y-389067D01*
X1259552Y-388122D01*
X1259160Y-387282D01*
X1258690Y-386862D01*
X1258142Y-386652D01*
X1257515Y-386862D01*
X1257045Y-387282D01*
X1256732Y-387912D01*
X1256575Y-388752D01*
X1256732Y-389487D01*
X1257124Y-390222D01*
X1257594Y-390642D01*
X1258142Y-390747D01*
X1258769Y-390537D01*
X1259239Y-390012D01*
X1259709Y-389067D01*
G01X1256810Y968413D02*
X1257359Y967888D01*
X1257985Y967678D01*
X1258612Y967888D01*
X1259160Y968518D01*
X1259552Y969463D01*
X1259709Y970408D01*
Y971563D01*
X1259552Y972508D01*
X1259160Y973348D01*
X1258690Y973768D01*
X1258142Y973978D01*
X1257515Y973768D01*
X1257045Y973348D01*
X1256732Y972718D01*
X1256575Y971878D01*
X1256732Y971143D01*
X1257124Y970408D01*
X1257594Y969988D01*
X1258142Y969883D01*
X1258769Y970093D01*
X1259239Y970618D01*
X1259709Y971563D01*
G01X1350418Y-296807D02*
Y-275748D01*
X1355682D01*
X1357788Y-276801D01*
X1359368Y-278205D01*
X1360684Y-280310D01*
X1361737Y-282768D01*
X1362000Y-286278D01*
X1361737Y-289788D01*
X1360684Y-292245D01*
X1359368Y-294351D01*
X1357788Y-295754D01*
X1355682Y-296807D01*
X1350418D01*
G01X1382006D02*
Y-282768D01*
G01Y-285224D02*
X1380953Y-283821D01*
X1379374Y-283119D01*
X1377531Y-282768D01*
X1375689Y-283470D01*
X1374109Y-284874D01*
X1373056Y-286980D01*
X1372530Y-289788D01*
X1373056Y-292595D01*
X1374109Y-294702D01*
X1375689Y-296105D01*
X1377531Y-296807D01*
X1379374Y-296456D01*
X1380953Y-295403D01*
X1382006Y-294000D01*
G01X1398327Y-275748D02*
Y-296807D01*
G01X1394642Y-282768D02*
X1402012D01*
G01X1415438Y-287331D02*
X1423861D01*
X1423071Y-284874D01*
X1421755Y-283470D01*
X1419913Y-282768D01*
X1418070Y-283119D01*
X1416490Y-284172D01*
X1415438Y-286629D01*
X1414911Y-288735D01*
Y-290840D01*
X1415438Y-292946D01*
X1416754Y-295052D01*
X1418333Y-296456D01*
X1420176Y-296807D01*
X1422018Y-296105D01*
X1423861Y-294000D01*
G01X1313635Y-227040D02*
Y-248099D01*
G01X1307581Y-227040D02*
X1319689D01*
G01X1330219Y-248099D02*
Y-227040D01*
G01Y-237218D02*
X1331535Y-235464D01*
X1332852Y-234411D01*
X1334957Y-234060D01*
X1336536Y-234411D01*
X1338379Y-235815D01*
X1339169Y-237921D01*
Y-248099D01*
G01X1355753Y-234060D02*
Y-248099D01*
G01Y-228444D02*
X1355226Y-228093D01*
Y-227391D01*
X1355753Y-227040D01*
X1356280Y-227391D01*
Y-228093D01*
X1355753Y-228444D01*
G01X1381024Y-235815D02*
X1379181Y-234411D01*
X1377602Y-234060D01*
X1375496Y-234762D01*
X1373916Y-236166D01*
X1372864Y-238623D01*
X1372600Y-241080D01*
X1372864Y-243537D01*
X1373916Y-245643D01*
X1375496Y-247397D01*
X1377602Y-248099D01*
X1379444Y-247397D01*
X1381024Y-245994D01*
G01X1393396Y-248099D02*
Y-227040D01*
G01X1401819Y-234060D02*
X1393396Y-242132D01*
G01X1396818Y-238973D02*
X1402346Y-248099D01*
G01X1414455D02*
Y-234060D01*
G01Y-237570D02*
X1415508Y-235815D01*
X1417088Y-234411D01*
X1419193Y-234060D01*
X1421036Y-234411D01*
X1422615Y-235815D01*
X1423405Y-238272D01*
Y-248099D01*
G01X1436041Y-238623D02*
X1444464D01*
X1443674Y-236166D01*
X1442358Y-234762D01*
X1440516Y-234060D01*
X1438673Y-234411D01*
X1437093Y-235464D01*
X1436041Y-237921D01*
X1435514Y-240027D01*
Y-242132D01*
X1436041Y-244238D01*
X1437357Y-246344D01*
X1438936Y-247748D01*
X1440779Y-248099D01*
X1442621Y-247397D01*
X1444464Y-245292D01*
G01X1457100Y-245643D02*
X1458416Y-247046D01*
X1460258Y-248099D01*
X1461838D01*
X1463417Y-247397D01*
X1464470Y-246344D01*
X1464996Y-244941D01*
X1464733Y-242834D01*
X1463680Y-241781D01*
X1458942Y-239676D01*
X1457889Y-237218D01*
X1458416Y-235464D01*
X1459469Y-234411D01*
X1461048Y-234060D01*
X1462627Y-234411D01*
X1464207Y-235464D01*
G01X1478159Y-245643D02*
X1479475Y-247046D01*
X1481317Y-248099D01*
X1482897D01*
X1484476Y-247397D01*
X1485529Y-246344D01*
X1486055Y-244941D01*
X1485792Y-242834D01*
X1484739Y-241781D01*
X1480001Y-239676D01*
X1478948Y-237218D01*
X1479475Y-235464D01*
X1480528Y-234411D01*
X1482107Y-234060D01*
X1483686Y-234411D01*
X1485266Y-235464D01*
G01X1431370Y-392952D02*
Y-386652D01*
X1430430Y-387912D01*
G01Y-392952D02*
X1432310D01*
G01X1437670Y-386652D02*
X1437043Y-386862D01*
X1436573Y-387387D01*
X1436260Y-388017D01*
X1436025Y-388857D01*
X1435947Y-389802D01*
X1436025Y-390747D01*
X1436260Y-391587D01*
X1436573Y-392217D01*
X1437043Y-392742D01*
X1437670Y-392952D01*
X1438297Y-392742D01*
X1438767Y-392217D01*
X1439080Y-391587D01*
X1439315Y-390747D01*
X1439393Y-389802D01*
X1439315Y-388857D01*
X1439080Y-388017D01*
X1438767Y-387387D01*
X1438297Y-386862D01*
X1437670Y-386652D01*
G01X1431370Y967678D02*
Y973978D01*
X1430430Y972718D01*
G01Y967678D02*
X1432310D01*
G01X1437670Y973978D02*
X1437043Y973768D01*
X1436573Y973243D01*
X1436260Y972613D01*
X1436025Y971773D01*
X1435947Y970828D01*
X1436025Y969883D01*
X1436260Y969043D01*
X1436573Y968413D01*
X1437043Y967888D01*
X1437670Y967678D01*
X1438297Y967888D01*
X1438767Y968413D01*
X1439080Y969043D01*
X1439315Y969883D01*
X1439393Y970828D01*
X1439315Y971773D01*
X1439080Y972613D01*
X1438767Y973243D01*
X1438297Y973768D01*
X1437670Y973978D01*
G01X1518625Y-277283D02*
X1520205Y-275177D01*
X1522048Y-274124D01*
X1524154Y-273773D01*
X1526786Y-274475D01*
X1528629Y-276230D01*
X1529155Y-278335D01*
X1528892Y-280442D01*
X1527839Y-282197D01*
X1522574Y-285706D01*
X1520205Y-288163D01*
X1518625Y-291674D01*
X1518099Y-294832D01*
X1529155D01*
G01X1544686Y-273773D02*
X1542580Y-274475D01*
X1541001Y-276230D01*
X1539948Y-278335D01*
X1539158Y-281144D01*
X1538895Y-284303D01*
X1539158Y-287462D01*
X1539948Y-290270D01*
X1541001Y-292376D01*
X1542580Y-294130D01*
X1544686Y-294832D01*
X1546792Y-294130D01*
X1548371Y-292376D01*
X1549424Y-290270D01*
X1550214Y-287462D01*
X1550477Y-284303D01*
X1550214Y-281144D01*
X1549424Y-278335D01*
X1548371Y-276230D01*
X1546792Y-274475D01*
X1544686Y-273773D01*
G01X1565745Y-294832D02*
Y-273773D01*
X1562586Y-277985D01*
G01Y-294832D02*
X1568903D01*
G01X1581802Y-286058D02*
X1583645Y-283600D01*
X1585225Y-282197D01*
X1587331Y-281495D01*
X1589173Y-282197D01*
X1590489Y-283600D01*
X1591542Y-285706D01*
X1591806Y-288163D01*
X1591542Y-290270D01*
X1590489Y-292376D01*
X1588910Y-294130D01*
X1587067Y-294832D01*
X1584962Y-294130D01*
X1583119Y-292025D01*
X1582066Y-288865D01*
X1581802Y-285356D01*
X1582329Y-280793D01*
X1583119Y-278335D01*
X1584435Y-275879D01*
X1586277Y-274124D01*
X1588120Y-273773D01*
X1589963Y-274475D01*
X1591279Y-276230D01*
G01X1604441Y-287813D02*
X1611285D01*
G01X1628922Y-294832D02*
X1630764Y-294481D01*
X1632870Y-293428D01*
X1634187Y-291674D01*
X1634713Y-289216D01*
X1634187Y-286760D01*
X1632607Y-284654D01*
X1630238Y-283600D01*
X1627606D01*
X1626026Y-282899D01*
X1624710Y-281144D01*
X1624184Y-278687D01*
X1624974Y-276230D01*
X1626816Y-274475D01*
X1628922Y-273773D01*
X1631028Y-274475D01*
X1632870Y-276230D01*
X1633660Y-278687D01*
X1633134Y-281144D01*
X1631818Y-282899D01*
X1630238Y-283600D01*
X1627606D01*
X1625237Y-284654D01*
X1623657Y-286760D01*
X1623131Y-289216D01*
X1623657Y-291674D01*
X1624974Y-293428D01*
X1627080Y-294481D01*
X1628922Y-294832D01*
G01X1646559Y-287813D02*
X1653403D01*
G01X1671040Y-294832D02*
Y-273773D01*
X1667881Y-277985D01*
G01Y-294832D02*
X1674198D01*
G01X1692099Y-273773D02*
X1689993Y-274475D01*
X1688414Y-276230D01*
X1687361Y-278335D01*
X1686571Y-281144D01*
X1686308Y-284303D01*
X1686571Y-287462D01*
X1687361Y-290270D01*
X1688414Y-292376D01*
X1689993Y-294130D01*
X1692099Y-294832D01*
X1694205Y-294130D01*
X1695784Y-292376D01*
X1696837Y-290270D01*
X1697627Y-287462D01*
X1697890Y-284303D01*
X1697627Y-281144D01*
X1696837Y-278335D01*
X1695784Y-276230D01*
X1694205Y-274475D01*
X1692099Y-273773D01*
G01X1531521Y-246124D02*
Y-225065D01*
X1528362Y-229277D01*
G01Y-246124D02*
X1534679D01*
G01X1552580Y-246826D02*
X1552053Y-246475D01*
Y-245773D01*
X1552580Y-245422D01*
X1553107Y-245773D01*
Y-246475D01*
X1552580Y-246826D01*
G01X1567848Y-242966D02*
X1569427Y-244720D01*
X1571270Y-245773D01*
X1573639Y-246124D01*
X1576008Y-245422D01*
X1577851Y-244019D01*
X1579167Y-241562D01*
X1579430Y-238754D01*
X1578904Y-235946D01*
X1577587Y-234191D01*
X1575745Y-232787D01*
X1573902Y-232436D01*
X1572060Y-232787D01*
X1569691Y-234191D01*
X1570480Y-225065D01*
X1577587D01*
G01X1594171Y-246124D02*
X1594698Y-241562D01*
X1595488Y-237701D01*
X1596540Y-234191D01*
X1597857Y-230330D01*
X1599963Y-225065D01*
X1589433D01*
G01X1607860Y-246124D02*
Y-232085D01*
G01Y-235946D02*
X1608650Y-234191D01*
X1609966Y-232787D01*
X1611809Y-232085D01*
X1613651Y-232787D01*
X1614967Y-234191D01*
X1615757Y-235946D01*
Y-246124D01*
G01Y-235946D02*
X1616547Y-234191D01*
X1617863Y-232787D01*
X1619705Y-232085D01*
X1621548Y-232787D01*
X1622864Y-234191D01*
X1623654Y-236297D01*
Y-246124D01*
G01X1628919D02*
Y-232085D01*
G01Y-235946D02*
X1629709Y-234191D01*
X1631025Y-232787D01*
X1632868Y-232085D01*
X1634710Y-232787D01*
X1636026Y-234191D01*
X1636816Y-235946D01*
Y-246124D01*
G01Y-235946D02*
X1637606Y-234191D01*
X1638922Y-232787D01*
X1640764Y-232085D01*
X1642607Y-232787D01*
X1643923Y-234191D01*
X1644713Y-236297D01*
Y-246124D01*
G01X1604598Y-392952D02*
Y-386652D01*
X1603658Y-387912D01*
G01Y-392952D02*
X1605538D01*
G01X1610898D02*
Y-386652D01*
X1609958Y-387912D01*
G01Y-392952D02*
X1611838D01*
G01X1604598Y967678D02*
Y973978D01*
X1603658Y972718D01*
G01Y967678D02*
X1605538D01*
G01X1610898D02*
Y973978D01*
X1609958Y972718D01*
G01Y967678D02*
X1611838D01*
G01X1734055Y-322874D02*
Y-316574D01*
X1737031D01*
G01X1735935Y-319619D02*
X1734055D01*
G01X1737110Y-86653D02*
X1733976D01*
Y-80353D01*
X1737110D01*
G01X1735856Y-83398D02*
X1733976D01*
G01X1733820Y149567D02*
Y155867D01*
X1735386D01*
X1736013Y155552D01*
X1736483Y155132D01*
X1736875Y154502D01*
X1737188Y153767D01*
X1737266Y152717D01*
X1737188Y151667D01*
X1736875Y150932D01*
X1736483Y150302D01*
X1736013Y149882D01*
X1735386Y149567D01*
X1733820D01*
G01X1737266Y391563D02*
X1736796Y391878D01*
X1736248Y392088D01*
X1735621D01*
X1734916Y391773D01*
X1734368Y391248D01*
X1733976Y390618D01*
X1733663Y389568D01*
X1733585Y388623D01*
X1733741Y387678D01*
X1733976Y387048D01*
X1734446Y386418D01*
X1734995Y385998D01*
X1735543Y385788D01*
X1736091D01*
X1736640Y385998D01*
X1737110Y386313D01*
X1737501Y386733D01*
G01X1736170Y625368D02*
X1736483Y625683D01*
X1736718Y626208D01*
X1736875Y626943D01*
X1736718Y627573D01*
X1736405Y627993D01*
X1735856Y628308D01*
X1733741D01*
Y622008D01*
X1736326D01*
X1736875Y622428D01*
X1737188Y623058D01*
X1737345Y623793D01*
X1737188Y624528D01*
X1736718Y625158D01*
X1736170Y625368D01*
X1733741D01*
G01X1733585Y858229D02*
X1735543Y864529D01*
X1737501Y858229D01*
G01X1736796Y860434D02*
X1734290D01*
G01X-221648Y-399206D02*
X1746854D01*
G01X-221648Y978747D02*
Y-399206D01*
G01Y-202356D02*
X-204326D01*
G01X-221648Y33865D02*
X-204326D01*
G01X-221648Y270085D02*
X-204326D01*
G01X-221648Y506306D02*
X-204326D01*
G01X-221648Y742526D02*
X-204326D01*
G01X-221648Y978747D02*
X1746854D01*
G01X-204326Y-381883D02*
X1729532D01*
G01X-204326Y961424D02*
Y-381883D01*
G01Y961424D02*
X1729532D01*
G01X-48421Y-381883D02*
Y-399206D01*
G01X7628Y-19685D02*
X-34432D01*
G01X3691Y0D02*
X-34432D01*
G01X29827Y-9492D02*
G03I-4000J0D01*
G01X27827D02*
G03I-2000J0D01*
G01X10612Y-28707D02*
X-25588D01*
G01X25827Y-13492D02*
X10612Y-28707D01*
G01X18757Y-17027D02*
X25827Y-13492D01*
G01D02*
X22292Y-20562D01*
G01D02*
X18757Y-17027D01*
G01X0Y-11811D02*
G03X7874Y-19685I7874J0D01*
G01X37008Y0D02*
G03Y-7874I0J-3937D01*
G01X11811D02*
G03Y0I0J3937D01*
G01X0Y-7874D02*
Y-11811D01*
G01X7874Y-19685D02*
X181690D01*
G01X0Y-7874D02*
X11811D01*
G01X22309Y26890D02*
X21927D01*
G01D02*
Y29382D01*
G01D02*
X22309D01*
G01D02*
Y29149D01*
G01D02*
X22461Y29305D01*
G01D02*
X22690Y29382D01*
G01D02*
X22995D01*
G01D02*
X23224Y29305D01*
G01D02*
X23453Y29071D01*
G01D02*
X23681Y29305D01*
G01D02*
X23911Y29382D01*
G01D02*
X24216D01*
G01D02*
X24444Y29305D01*
G01D02*
X24597Y29149D01*
G01D02*
X24750Y28759D01*
G01D02*
Y26890D01*
G01D02*
X24368D01*
G01D02*
Y28759D01*
G01D02*
X24292Y28915D01*
G01D02*
X24216Y28993D01*
G01D02*
X24063Y29071D01*
G01D02*
X23834D01*
G01D02*
X23681Y28993D01*
G01D02*
X23605Y28915D01*
G01D02*
X23529Y28759D01*
G01D02*
Y26890D01*
G01D02*
X23148D01*
G01D02*
Y28759D01*
G01D02*
X23071Y28915D01*
G01D02*
X22995Y28993D01*
G01D02*
X22842Y29071D01*
G01D02*
X22690D01*
G01D02*
X22461Y28993D01*
G01D02*
X22309Y28837D01*
G01D02*
Y26890D01*
G01X18876D02*
X18494D01*
G01D02*
Y29382D01*
G01D02*
X18876D01*
G01D02*
Y29149D01*
G01D02*
X19029Y29305D01*
G01D02*
X19257Y29382D01*
G01D02*
X19563D01*
G01D02*
X19791Y29305D01*
G01D02*
X20020Y29071D01*
G01D02*
X20249Y29305D01*
G01D02*
X20478Y29382D01*
G01D02*
X20783D01*
G01D02*
X21012Y29305D01*
G01D02*
X21165Y29149D01*
G01D02*
X21317Y28759D01*
G01D02*
Y26890D01*
G01D02*
X20935D01*
G01D02*
Y28759D01*
G01D02*
X20859Y28915D01*
G01D02*
X20783Y28993D01*
G01D02*
X20630Y29071D01*
G01D02*
X20402D01*
G01D02*
X20249Y28993D01*
G01D02*
X20173Y28915D01*
G01D02*
X20096Y28759D01*
G01D02*
Y26890D01*
G01D02*
X19715D01*
G01D02*
Y28759D01*
G01D02*
X19639Y28915D01*
G01D02*
X19563Y28993D01*
G01D02*
X19410Y29071D01*
G01D02*
X19257D01*
G01D02*
X19029Y28993D01*
G01D02*
X18876Y28837D01*
G01D02*
Y26890D01*
G01X15520Y28993D02*
Y28447D01*
G01D02*
X15596Y27980D01*
G01D02*
X15901Y27513D01*
G01D02*
X16130Y27357D01*
G01D02*
X16511Y27279D01*
G01D02*
X16893Y27357D01*
G01D02*
X17122Y27513D01*
G01D02*
X17427Y27980D01*
G01D02*
X17503Y28447D01*
G01D02*
Y28993D01*
G01D02*
X17427Y29460D01*
G01D02*
X17122Y29928D01*
G01D02*
X16893Y30083D01*
G01D02*
X16511Y30161D01*
G01D02*
X16130Y30083D01*
G01D02*
X15901Y29928D01*
G01D02*
X15596Y29460D01*
G01D02*
X15520Y28993D01*
G01X15215Y29460D02*
X15138Y29071D01*
G01X15291Y29694D02*
X15215Y29460D01*
G01X15443Y30006D02*
X15291Y29694D01*
G01X15672Y30239D02*
X15443Y30006D01*
G01X16053Y30473D02*
X15672Y30239D01*
G01X16511Y30551D02*
X16053Y30473D01*
G01X16969D02*
X16511Y30551D01*
G01X17350Y30239D02*
X16969Y30473D01*
G01X17579Y30006D02*
X17350Y30239D01*
G01X17732Y29694D02*
X17579Y30006D01*
G01X17808Y29460D02*
X17732Y29694D01*
G01X17884Y29071D02*
X17808Y29460D01*
G01X17884Y28369D02*
Y29071D01*
G01X17808Y27980D02*
X17884Y28369D01*
G01X17732Y27746D02*
X17808Y27980D01*
G01X17579Y27435D02*
X17732Y27746D01*
G01X17350Y27201D02*
X17579Y27435D01*
G01X16969Y26967D02*
X17350Y27201D01*
G01X16511Y26890D02*
X16969Y26967D01*
G01X16053D02*
X16511Y26890D01*
G01X15672Y27201D02*
X16053Y26967D01*
G01X15443Y27435D02*
X15672Y27201D01*
G01X15291Y27746D02*
X15443Y27435D01*
G01X15215Y27980D02*
X15291Y27746D01*
G01X15138Y28369D02*
X15215Y27980D01*
G01X15138Y29071D02*
Y28369D01*
G01X13307Y28447D02*
X14528D01*
G01D02*
Y28136D01*
G01D02*
X13307D01*
G01D02*
Y28447D01*
G01Y29382D02*
X14528D01*
G01D02*
Y29071D01*
G01D02*
X13307D01*
G01D02*
Y29382D01*
G01X10104Y26890D02*
X9646D01*
G01D02*
Y30551D01*
G01D02*
X10104D01*
G01D02*
Y29071D01*
G01D02*
X12240D01*
G01D02*
Y30551D01*
G01D02*
X12697D01*
G01D02*
Y26890D01*
G01D02*
X12240D01*
G01D02*
Y28603D01*
G01D02*
X10104D01*
G01D02*
Y26890D01*
G01X33342Y17716D02*
X27361D01*
G01X19685Y10041D02*
G03X27361Y17716I-1968J9644D01*
G01X19685Y10041D02*
Y4060D01*
G01X15748D02*
Y10041D01*
G01X8073Y17716D02*
G03X15748Y10041I9644J1969D01*
G01X8073Y17716D02*
X2092D01*
G01Y21653D02*
X8073D01*
G01X15748Y29329D02*
G03X8073Y21653I1969J-9644D01*
G01X15748Y29329D02*
Y35309D01*
G01X19685D02*
Y29329D01*
G01X27361Y21653D02*
G03X19685Y29329I-9644J-1968D01*
G01X27361Y21653D02*
X33342D01*
G01X7874Y19685D02*
G03X27559I9842J0D01*
G01D02*
G03X7874I-9843J0D01*
G01X15748Y4060D02*
G03X19685I1969J15625D01*
G01X1969Y19685D02*
G03X2092Y17716I15748J-5D01*
G01Y21653D02*
G03X1969Y19685I15625J-1964D01*
G01X25985D02*
G03X9449I-8268J0D01*
G01D02*
G03X25985I8268J0D01*
G01X19685Y10041D02*
G03X27361Y17716I-1968J9644D01*
G01X33342D02*
X27361D01*
G01X19685Y4060D02*
G03X33342Y17716I-1968J15625D01*
G01X19685Y10041D02*
Y4060D01*
G01X8073Y17716D02*
G03X15748Y10041I9644J1969D01*
G01Y4060D02*
Y10041D01*
G01X2092Y17716D02*
G03X15748Y4060I15625J1969D01*
G01X8073Y17716D02*
X2092D01*
G01X15748Y29329D02*
G03X8073Y21653I1969J-9644D01*
G01X2092D02*
X8073D01*
G01X15748Y35309D02*
G03X2092Y21653I1969J-15625D01*
G01X15748Y29329D02*
Y35309D01*
G01X33342Y21653D02*
G03X19685Y35309I-15625J-1969D01*
G01X27361Y21653D02*
X33342D01*
G01X27361D02*
G03X19685Y29329I-9644J-1968D01*
G01Y35309D02*
Y29329D01*
G01X27814Y13287D02*
G03X29782I984J0D01*
G01D02*
G03X27814I-984J0D01*
G01X23130Y8604D02*
G03X25099I985J0D01*
G01D02*
G03X23130I-984J0D01*
G01X5652Y13287D02*
G03X7620I984J0D01*
G01D02*
G03X5652I-984J0D01*
G01X10335Y8604D02*
G03X12303I984J0D01*
G01D02*
G03X10335I-984J0D01*
G01X27814Y26082D02*
G03X29782I984J0D01*
G01D02*
G03X27814I-984J0D01*
G01X23130Y30766D02*
G03X25099I985J0D01*
G01D02*
G03X23130I-984J0D01*
G01X5652Y26082D02*
G03X7620I984J0D01*
G01D02*
G03X5652I-984J0D01*
G01X10335Y30766D02*
G03X12303I984J0D01*
G01D02*
G03X10335I-984J0D01*
G01X27814Y13287D02*
G03X29782I984J0D01*
G01D02*
G03X27814I-984J0D01*
G01X23130Y8604D02*
G03X25099I985J0D01*
G01D02*
G03X23130I-984J0D01*
G01X5652Y13287D02*
G03X7620I984J0D01*
G01D02*
G03X5652I-984J0D01*
G01X10335Y8604D02*
G03X12303I984J0D01*
G01D02*
G03X10335I-984J0D01*
G01X27814Y26082D02*
G03X29782I984J0D01*
G01D02*
G03X27814I-984J0D01*
G01X23130Y30766D02*
G03X25099I985J0D01*
G01D02*
G03X23130I-984J0D01*
G01X5652Y26082D02*
G03X7620I984J0D01*
G01D02*
G03X5652I-984J0D01*
G01X10335Y30766D02*
G03X12303I984J0D01*
G01D02*
G03X10335I-984J0D01*
G01X25985Y19685D02*
G03X9449I-8268J0D01*
G01D02*
G03X25985I8268J0D01*
G01D02*
G03X9449I-8268J0D01*
G01D02*
G03X25985I8268J0D01*
G01X27814Y13287D02*
G03X29782I984J0D01*
G01D02*
G03X27814I-984J0D01*
G01X23130Y8604D02*
G03X25099I985J0D01*
G01D02*
G03X23130I-984J0D01*
G01X5652Y13287D02*
G03X7620I984J0D01*
G01D02*
G03X5652I-984J0D01*
G01X10335Y8604D02*
G03X12303I984J0D01*
G01D02*
G03X10335I-984J0D01*
G01X27814Y26082D02*
G03X29782I984J0D01*
G01D02*
G03X27814I-984J0D01*
G01X23130Y30766D02*
G03X25099I985J0D01*
G01D02*
G03X23130I-984J0D01*
G01X5652Y26082D02*
G03X7620I984J0D01*
G01D02*
G03X5652I-984J0D01*
G01X10335Y30766D02*
G03X12303I984J0D01*
G01D02*
G03X10335I-984J0D01*
G01X7874Y19685D02*
G03X27559I9842J0D01*
G01D02*
G03X7874I-9843J0D01*
G01X27814Y13287D02*
G03X29782I984J0D01*
G01D02*
G03X27814I-984J0D01*
G01X23130Y8604D02*
G03X25099I985J0D01*
G01D02*
G03X23130I-984J0D01*
G01X5652Y13287D02*
G03X7620I984J0D01*
G01D02*
G03X5652I-984J0D01*
G01X10335Y8604D02*
G03X12303I984J0D01*
G01D02*
G03X10335I-984J0D01*
G01X27814Y26082D02*
G03X29782I984J0D01*
G01D02*
G03X27814I-984J0D01*
G01X23130Y30766D02*
G03X25099I985J0D01*
G01D02*
G03X23130I-984J0D01*
G01X5652Y26082D02*
G03X7620I984J0D01*
G01D02*
G03X5652I-984J0D01*
G01X10335Y30766D02*
G03X12303I984J0D01*
G01D02*
G03X10335I-984J0D01*
G01X25985Y19685D02*
G03X9449I-8268J0D01*
G01D02*
G03X25985I8268J0D01*
G01X9449D02*
G03X25985I8268J0D01*
G01D02*
G03X9449I-8268J0D01*
G01D02*
G03X25985I8268J0D01*
G01D02*
G03X9449I-8268J0D01*
G01X3937Y0D02*
X173229D01*
G01X0Y3937D02*
G03X3937Y0I3937J0D01*
G01X0Y57874D02*
Y3937D01*
G01X29291Y54311D02*
G03X22913Y47933I0J-6378D01*
G01Y45965D02*
G03X29291Y39587I6378J0D01*
G01X22913Y45965D02*
Y47933D01*
G01X30256Y48130D02*
G03X29469Y47343I0J-787D01*
G01Y46555D02*
G03X30256Y45768I787J0D01*
G01X27480Y46949D02*
G03I-590J0D01*
G01X30059Y48327D02*
G03X29469Y47736I1J-591D01*
G01Y46161D02*
G03X30059Y45571I590J0D01*
G01X29272Y48130D02*
G03X28484Y47343I0J-788D01*
G01Y46555D02*
G03X29272Y45768I787J0D01*
G01X27874Y46949D02*
G03I-984J0D01*
G01X30059Y49311D02*
G03X28484Y47736I0J-1575D01*
G01Y46161D02*
G03X30059Y44587I1575J1D01*
G01X29094Y51988D02*
G03X25236Y48130I0J-3858D01*
G01Y45768D02*
G03X29094Y41909I3859J0D01*
G01Y52579D02*
G03X24646Y48130I1J-4449D01*
G01Y45768D02*
G03X29094Y41319I4449J0D01*
G01Y53169D02*
G03X24055Y48130I0J-5039D01*
G01Y45768D02*
G03X29094Y40728I5040J0D01*
G01X35354Y55906D02*
X29291D01*
G01X35354Y54921D02*
X29291D01*
G01X35354Y54843D02*
X29291D01*
G01X54016Y54311D02*
X29291D01*
G01X54213Y53169D02*
X29094D01*
G01Y52579D02*
X54213D01*
G01Y51988D02*
X29094D01*
G01X32402Y51594D02*
X33189D01*
G01X30433D02*
X31220D01*
G01X29679Y50732D02*
X29526D01*
G01X29272Y48130D02*
X29130Y48115D01*
X28993Y48070D01*
X28867Y47998D01*
X28755Y47899D01*
X28664Y47781D01*
X28597Y47645D01*
X28555Y47498D01*
X28541Y47343D01*
G01X29272Y48130D02*
X29097Y48110D01*
X28930Y48052D01*
X28781Y47958D01*
X28656Y47833D01*
X28562Y47684D01*
X28504Y47517D01*
X28484Y47343D01*
G01X32402Y49705D02*
X33189D01*
G01X30433D02*
X31220D01*
G01X29526Y49512D02*
X29679D01*
G01X30059Y49311D02*
X53248D01*
G01X31220Y48839D02*
X30433D01*
G01X33189D02*
X32402D01*
G01X53248Y48327D02*
X30059D01*
G01X25236Y48130D02*
X24646D01*
G01X54035D02*
X29272D01*
G01X29469Y47736D02*
X28484D01*
G01X54823Y47343D02*
X28484D01*
G01X53760Y47185D02*
X29547D01*
G01X53760Y46713D02*
X29547D01*
G01X28484Y46555D02*
X54823D01*
G01X28484Y46161D02*
X29469D01*
G01X24646Y45768D02*
X25236D01*
G01X54035D02*
X29272D01*
G01X30059Y45571D02*
X53248D01*
G01X31220Y45059D02*
X30433D01*
G01X33189D02*
X32402D01*
G01X53248Y44587D02*
X30059D01*
G01X29272Y45768D02*
X29097Y45787D01*
X28930Y45846D01*
X28781Y45939D01*
X28656Y46064D01*
X28562Y46214D01*
X28504Y46380D01*
X28484Y46555D01*
G01X30041Y45768D02*
X29899Y45783D01*
X29763Y45827D01*
X29637Y45899D01*
X29524Y45998D01*
X29433Y46117D01*
X29366Y46252D01*
X29324Y46400D01*
X29310Y46555D01*
G01X32402Y44193D02*
X33189D01*
G01X30433D02*
X31220D01*
G01X32402Y42303D02*
X33189D01*
G01X30433D02*
X31220D01*
G01X54213Y41909D02*
X29094D01*
G01X54213Y41319D02*
X29094D01*
G01X54213Y40728D02*
X29094D01*
G01X29291Y39587D02*
X54016D01*
G01X35354Y39055D02*
X29291D01*
G01Y38976D02*
X35354D01*
G01Y37992D02*
X29291D01*
G01X29526Y49720D02*
X29374Y49901D01*
G01Y49694D02*
X29526Y49512D01*
G01X33189Y45059D02*
Y42303D01*
G01Y51594D02*
Y48839D01*
G01X29310Y47343D02*
X29324Y47495D01*
X29365Y47643D01*
X29432Y47778D01*
X29524Y47899D01*
X29634Y47997D01*
X29760Y48069D01*
X29896Y48114D01*
X30041Y48130D01*
G01X32992Y37992D02*
Y38976D01*
G01Y55906D02*
Y54921D01*
G01X32894Y37992D02*
Y38976D01*
G01Y55906D02*
Y54921D01*
G01X32795D02*
Y55906D01*
G01Y37992D02*
Y38976D01*
G01X32402Y45059D02*
Y42303D01*
G01Y51594D02*
Y48839D01*
G01X31614Y54921D02*
Y55906D01*
G01Y37992D02*
Y38976D01*
G01X31516Y37992D02*
Y38976D01*
G01Y55906D02*
Y54921D01*
G01X31417Y37992D02*
Y38976D01*
G01Y55906D02*
Y54921D01*
G01X31220Y45059D02*
Y42303D01*
G01Y51594D02*
Y48839D01*
G01X30630Y37992D02*
Y38976D01*
G01Y55906D02*
Y54921D01*
G01X30433Y45059D02*
Y42303D01*
G01Y51594D02*
Y48839D01*
G01X30138Y46713D02*
Y47185D01*
G01X30079Y38976D02*
Y37992D01*
G01Y55906D02*
Y54921D01*
G01X30059Y48327D02*
Y49311D01*
G01Y45571D02*
Y44587D01*
G01X30041Y45768D02*
Y48130D01*
G01X29679Y49512D02*
Y50732D01*
G01X29547Y47185D02*
Y46713D01*
G01X29526Y50732D02*
Y49720D01*
G01X29469Y46161D02*
Y47736D01*
G01X29374Y49901D02*
Y49694D01*
G01X29310Y46555D02*
Y47343D01*
G01X29291Y39587D02*
Y37992D01*
G01Y55906D02*
Y54311D01*
G01X29154Y54309D02*
Y39588D01*
G01X29094Y41909D02*
Y41319D01*
G01Y52579D02*
Y51988D01*
G01X28541Y46555D02*
Y47343D01*
G01X28484Y46161D02*
Y47736D01*
G01X28541Y46555D02*
X28555Y46402D01*
X28596Y46255D01*
X28663Y46119D01*
X28755Y45998D01*
X28865Y45901D01*
X28991Y45828D01*
X29127Y45783D01*
X29272Y45768D01*
G01X25236D02*
Y48130D01*
G01X24646Y45768D02*
Y48130D01*
G01X24055Y45768D02*
Y48130D01*
G01X3691Y61811D02*
X-34432D01*
G01X-33014Y70801D02*
X-34432D01*
G01X-31597Y69685D02*
X-33014Y70801D01*
G01X3691Y69685D02*
X-31597D01*
G01X37008D02*
G03Y61811I0J-3937D01*
G01X11811D02*
G03Y69685I0J3937D01*
G01X25985Y89370D02*
G03X9449I-8268J0D01*
G01D02*
G03X25985I8268J0D01*
G01D02*
G03X9449I-8268J0D01*
G01D02*
G03X25985I8268J0D01*
G01D02*
G03X9449I-8268J0D01*
G01D02*
G03X25985I8268J0D01*
G01D02*
G03X9449I-8268J0D01*
G01D02*
G03X25985I8268J0D01*
G01X9449D02*
G03X25985I8268J0D01*
G01D02*
G03X9449I-8268J0D01*
G01D02*
G03X25985I8268J0D01*
G01D02*
G03X9449I-8268J0D01*
G01X3937Y69685D02*
X173229D01*
G01X0Y73622D02*
G03X3937Y69685I3937J0D01*
G01X0Y127559D02*
Y73622D01*
G01X19685Y35309D02*
G03X15748I-1969J-15624D01*
G01X3937Y61811D02*
G03X0Y57874I0J-3937D01*
G01X173229Y61811D02*
X3937D01*
G01X3691Y131496D02*
X-34432D01*
G01X-33014Y141763D02*
X-34432D01*
G01X-31597Y139370D02*
X-33014Y141763D01*
G01X3691Y139370D02*
X-31597D01*
G01X37008D02*
G03Y131496I0J-3937D01*
G01X11811D02*
G03Y139370I0J3937D01*
G01X25985Y159055D02*
G03X9449I-8268J0D01*
G01D02*
G03X25985I8268J0D01*
G01D02*
G03X9449I-8268J0D01*
G01D02*
G03X25985I8268J0D01*
G01D02*
G03X9449I-8268J0D01*
G01D02*
G03X25985I8268J0D01*
G01D02*
G03X9449I-8268J0D01*
G01D02*
G03X25985I8268J0D01*
G01X9449D02*
G03X25985I8268J0D01*
G01D02*
G03X9449I-8268J0D01*
G01D02*
G03X25985I8268J0D01*
G01D02*
G03X9449I-8268J0D01*
G01X3937Y139370D02*
X173229D01*
G01X0Y143307D02*
G03X3937Y139370I3937J0D01*
G01X0Y197244D02*
Y143307D01*
G01X3937Y131496D02*
G03X0Y127559I0J-3937D01*
G01X173229Y131496D02*
X3937D01*
G01X3691Y201181D02*
X-34432D01*
G01X-33014Y210688D02*
X-34432D01*
G01X-31597Y209055D02*
X-33014Y210688D01*
G01X3691Y209055D02*
X-31597D01*
G01X3691Y270866D02*
X-34432D01*
G01X-33014Y279802D02*
X-34432D01*
G01X-31597Y278740D02*
X-33014Y279802D01*
G01X3691Y278740D02*
X-31597D01*
G01X37008D02*
G03Y270866I0J-3937D01*
G01X11811D02*
G03Y278740I0J3937D01*
G01X37008Y209055D02*
G03Y201181I0J-3937D01*
G01X11811D02*
G03Y209055I0J3937D01*
G01X3937Y278740D02*
X173229D01*
G01X0Y282677D02*
G03X3937Y278740I3937J0D01*
G01X25985Y228740D02*
G03X9449I-8268J0D01*
G01D02*
G03X25985I8268J0D01*
G01D02*
G03X9449I-8268J0D01*
G01D02*
G03X25985I8268J0D01*
G01D02*
G03X9449I-8268J0D01*
G01D02*
G03X25985I8268J0D01*
G01D02*
G03X9449I-8268J0D01*
G01D02*
G03X25985I8268J0D01*
G01X9449D02*
G03X25985I8268J0D01*
G01D02*
G03X9449I-8268J0D01*
G01D02*
G03X25985I8268J0D01*
G01D02*
G03X9449I-8268J0D01*
G01X3937Y209055D02*
X173229D01*
G01X0Y212992D02*
G03X3937Y209055I3937J0D01*
G01X0Y266929D02*
Y212992D01*
G01X3937Y270866D02*
G03X0Y266929I0J-3937D01*
G01X173229Y270866D02*
X3937D01*
G01Y201181D02*
G03X0Y197244I0J-3937D01*
G01X173229Y201181D02*
X3937D01*
G01X3691Y340551D02*
X-34432D01*
G01X-33014Y349095D02*
X-34432D01*
G01X-31597Y348425D02*
X-33014Y349095D01*
G01X3691Y348425D02*
X-31597D01*
G01X37008D02*
G03Y340551I0J-3937D01*
G01X11811D02*
G03Y348425I0J3937D01*
G01X9449Y368110D02*
G03X25985I8268J0D01*
G01X9449D02*
G03X25985I8268J0D01*
G01X9449D02*
G03X25985I8268J0D01*
G01X9449D02*
G03X25985I8268J0D01*
G01X9449D02*
G03X25985I8268J0D01*
G01X9449D02*
G03X25985I8268J0D01*
G01X3937Y348425D02*
X173229D01*
G01X0Y352362D02*
G03X3937Y348425I3937J0D01*
G01X0Y406299D02*
Y352362D01*
G01X25985Y298425D02*
G03X9449I-8268J0D01*
G01D02*
G03X25985I8268J0D01*
G01D02*
G03X9449I-8268J0D01*
G01D02*
G03X25985I8268J0D01*
G01D02*
G03X9449I-8268J0D01*
G01D02*
G03X25985I8268J0D01*
G01D02*
G03X9449I-8268J0D01*
G01D02*
G03X25985I8268J0D01*
G01X9449D02*
G03X25985I8268J0D01*
G01D02*
G03X9449I-8268J0D01*
G01D02*
G03X25985I8268J0D01*
G01D02*
G03X9449I-8268J0D01*
G01X0Y336614D02*
Y282677D01*
G01X3937Y340551D02*
G03X0Y336614I0J-3937D01*
G01X173229Y340551D02*
X3937D01*
G01X3691Y410236D02*
X-34432D01*
G01X-33014Y419463D02*
X-34432D01*
G01X-31597Y418110D02*
X-33014Y419463D01*
G01X3691Y418110D02*
X-31597D01*
G01X37008D02*
G03Y410236I0J-3937D01*
G01X11811D02*
G03Y418110I0J3937D01*
G01X25985Y437795D02*
G03X9449I-8268J0D01*
G01D02*
G03X25985I8268J0D01*
G01D02*
G03X9449I-8268J0D01*
G01D02*
G03X25985I8268J0D01*
G01D02*
G03X9449I-8268J0D01*
G01D02*
G03X25985I8268J0D01*
G01D02*
G03X9449I-8268J0D01*
G01D02*
G03X25985I8268J0D01*
G01X9449D02*
G03X25985I8268J0D01*
G01D02*
G03X9449I-8268J0D01*
G01D02*
G03X25985I8268J0D01*
G01D02*
G03X9449I-8268J0D01*
G01X3937Y418110D02*
X173229D01*
G01X0Y422047D02*
G03X3937Y418110I3937J0D01*
G01X0Y475984D02*
Y422047D01*
G01X25985Y368110D02*
G03X9449I-8268J0D01*
G01X25985D02*
G03X9449I-8268J0D01*
G01X25985D02*
G03X9449I-8268J0D01*
G01X25985D02*
G03X9449I-8268J0D01*
G01X25985D02*
G03X9449I-8268J0D01*
G01X25985D02*
G03X9449I-8268J0D01*
G01X3937Y410236D02*
G03X0Y406299I0J-3937D01*
G01X173229Y410236D02*
X3937D01*
G01X3691Y479921D02*
X-34432D01*
G01X-33014Y489059D02*
X-34432D01*
G01X-31597Y487795D02*
X-33014Y489059D01*
G01X3691Y487795D02*
X-31597D01*
G01X37008D02*
G03Y479921I0J-3937D01*
G01X11811D02*
G03Y487795I0J3937D01*
G01X25985Y507480D02*
G03X9449I-8268J0D01*
G01D02*
G03X25985I8268J0D01*
G01D02*
G03X9449I-8268J0D01*
G01D02*
G03X25985I8268J0D01*
G01D02*
G03X9449I-8268J0D01*
G01D02*
G03X25985I8268J0D01*
G01D02*
G03X9449I-8268J0D01*
G01D02*
G03X25985I8268J0D01*
G01X9449D02*
G03X25985I8268J0D01*
G01D02*
G03X9449I-8268J0D01*
G01D02*
G03X25985I8268J0D01*
G01D02*
G03X9449I-8268J0D01*
G01X3937Y487795D02*
X173229D01*
G01X0Y491732D02*
G03X3937Y487795I3937J0D01*
G01X0Y545669D02*
Y491732D01*
G01X3937Y479921D02*
G03X0Y475984I0J-3937D01*
G01X173229Y479921D02*
X3937D01*
G01X3691Y549606D02*
X-34432D01*
G01X-33014Y558884D02*
X-34432D01*
G01X-31597Y557480D02*
X-33014Y558884D01*
G01X3691Y557480D02*
X-31597D01*
G01X37008D02*
G03Y549606I0J-3937D01*
G01X11811D02*
G03Y557480I0J3937D01*
G01X25985Y577165D02*
G03X9449I-8268J0D01*
G01D02*
G03X25985I8268J0D01*
G01D02*
G03X9449I-8268J0D01*
G01D02*
G03X25985I8268J0D01*
G01D02*
G03X9449I-8268J0D01*
G01D02*
G03X25985I8268J0D01*
G01D02*
G03X9449I-8268J0D01*
G01D02*
G03X25985I8268J0D01*
G01X9449D02*
G03X25985I8268J0D01*
G01D02*
G03X9449I-8268J0D01*
G01D02*
G03X25985I8268J0D01*
G01D02*
G03X9449I-8268J0D01*
G01X3937Y557480D02*
X173229D01*
G01X0Y561417D02*
G03X3937Y557480I3937J0D01*
G01X0Y615354D02*
Y561417D01*
G01X3937Y549606D02*
G03X0Y545669I0J-3937D01*
G01X173229Y549606D02*
X3937D01*
G01X3691Y619291D02*
X-34432D01*
G01X-33014Y629344D02*
X-34432D01*
G01X-31597Y627165D02*
X-33014Y629344D01*
G01X3691Y627165D02*
X-31597D01*
G01X3691Y688976D02*
X-34432D01*
G01X0Y685285D02*
Y719159D01*
G01X37008Y627165D02*
G03Y619291I0J-3937D01*
G01X11811D02*
G03Y627165I0J3937D01*
G01X25985Y646850D02*
G03X9449I-8268J0D01*
G01D02*
G03X25985I8268J0D01*
G01D02*
G03X9449I-8268J0D01*
G01D02*
G03X25985I8268J0D01*
G01D02*
G03X9449I-8268J0D01*
G01D02*
G03X25985I8268J0D01*
G01D02*
G03X9449I-8268J0D01*
G01D02*
G03X25985I8268J0D01*
G01X9449D02*
G03X25985I8268J0D01*
G01D02*
G03X9449I-8268J0D01*
G01D02*
G03X25985I8268J0D01*
G01D02*
G03X9449I-8268J0D01*
G01X3937Y627165D02*
X173229D01*
G01X0Y631102D02*
G03X3937Y627165I3937J0D01*
G01X0Y685039D02*
Y631102D01*
G01X3937Y688976D02*
G03X0Y685039I0J-3937D01*
G01X173229Y688976D02*
X3937D01*
G01Y619291D02*
G03X0Y615354I0J-3937D01*
G01X173229Y619291D02*
X3937D01*
G01X-48421Y978747D02*
Y961424D01*
G01X37008Y-7874D02*
X140158D01*
G01X102756Y5413D02*
Y5708D01*
G01D02*
X105118D01*
G01D02*
Y5413D01*
G01D02*
X103963D01*
G01D02*
X105118Y4330D01*
G01D02*
Y3937D01*
G01D02*
X104164Y4823D01*
G01D02*
X102756Y3937D01*
G01D02*
Y4330D01*
G01D02*
X103912Y5069D01*
G01D02*
X103561Y5413D01*
G01D02*
X102756D01*
G01X103561Y15206D02*
X104918Y14764D01*
G01X103561Y14321D02*
Y15206D01*
G01X104918Y14764D02*
X103561Y14321D01*
G01X105118Y14567D02*
X102756Y13779D01*
G01D02*
Y14075D01*
G01D02*
X103359Y14271D01*
G01D02*
Y15256D01*
G01D02*
X102756Y15453D01*
G01D02*
Y15748D01*
G01D02*
X105118Y14960D01*
G01D02*
Y14567D01*
G01X88583Y5413D02*
Y5708D01*
G01D02*
X90945D01*
G01D02*
Y5413D01*
G01D02*
X89789D01*
G01D02*
X90945Y4330D01*
G01D02*
Y3937D01*
G01D02*
X89991Y4823D01*
G01D02*
X88583Y3937D01*
G01D02*
Y4330D01*
G01D02*
X89739Y5069D01*
G01D02*
X89387Y5413D01*
G01D02*
X88583D01*
G01X89387Y15206D02*
X90744Y14764D01*
G01X89387Y14321D02*
Y15206D01*
G01X90744Y14764D02*
X89387Y14321D01*
G01X90945Y14567D02*
X88583Y13779D01*
G01D02*
Y14075D01*
G01D02*
X89186Y14271D01*
G01D02*
Y15256D01*
G01D02*
X88583Y15453D01*
G01D02*
Y15748D01*
G01D02*
X90945Y14960D01*
G01D02*
Y14567D01*
G01X74410Y5413D02*
Y5708D01*
G01D02*
X76772D01*
G01D02*
Y5413D01*
G01D02*
X75616D01*
G01D02*
X76772Y4330D01*
G01D02*
Y3937D01*
G01D02*
X75817Y4823D01*
G01D02*
X74410Y3937D01*
G01D02*
Y4330D01*
G01D02*
X75566Y5069D01*
G01D02*
X75214Y5413D01*
G01D02*
X74410D01*
G01X75214Y15206D02*
X76571Y14764D01*
G01X75214Y14321D02*
Y15206D01*
G01X76571Y14764D02*
X75214Y14321D01*
G01X76772Y14567D02*
X74410Y13779D01*
G01D02*
Y14075D01*
G01D02*
X75013Y14271D01*
G01D02*
Y15256D01*
G01D02*
X74410Y15453D01*
G01D02*
Y15748D01*
G01D02*
X76772Y14960D01*
G01D02*
Y14567D01*
G01X60237Y5413D02*
Y5708D01*
G01D02*
X62599D01*
G01D02*
Y5413D01*
G01D02*
X61443D01*
G01D02*
X62599Y4330D01*
G01D02*
Y3937D01*
G01D02*
X61644Y4823D01*
G01D02*
X60237Y3937D01*
G01D02*
Y4330D01*
G01D02*
X61392Y5069D01*
G01D02*
X61041Y5413D01*
G01D02*
X60237D01*
G01X61041Y15206D02*
X62398Y14764D01*
G01X61041Y14321D02*
Y15206D01*
G01X62398Y14764D02*
X61041Y14321D01*
G01X62599Y14567D02*
X60237Y13779D01*
G01D02*
Y14075D01*
G01D02*
X60840Y14271D01*
G01D02*
Y15256D01*
G01D02*
X60237Y15453D01*
G01D02*
Y15748D01*
G01D02*
X62599Y14960D01*
G01D02*
Y14567D01*
G01X46063Y5413D02*
Y5708D01*
G01D02*
X48426D01*
G01D02*
Y5413D01*
G01D02*
X47270D01*
G01D02*
X48426Y4330D01*
G01D02*
Y3937D01*
G01D02*
X47471Y4823D01*
G01D02*
X46063Y3937D01*
G01D02*
Y4330D01*
G01D02*
X47219Y5069D01*
G01D02*
X46868Y5413D01*
G01D02*
X46063D01*
G01X46868Y15206D02*
X48225Y14764D01*
G01X46868Y14321D02*
Y15206D01*
G01X48225Y14764D02*
X46868Y14321D01*
G01X48426Y14567D02*
X46063Y13779D01*
G01D02*
Y14075D01*
G01D02*
X46666Y14271D01*
G01D02*
Y15256D01*
G01D02*
X46063Y15453D01*
G01D02*
Y15748D01*
G01D02*
X48426Y14960D01*
G01D02*
Y14567D01*
G01X118111Y12632D02*
G03Y7052I0J-2790D01*
G01X114961Y9842D02*
Y3543D01*
G01D02*
X121260D01*
G01X114961Y9842D02*
G03X118111Y6693I3149J0D01*
G01X121260Y16142D02*
X114961D01*
G01D02*
Y9842D01*
G01X118111Y12992D02*
G03X114961Y9842I0J-3150D01*
G01Y3543D02*
X121260D01*
G01X114961Y16142D02*
Y3543D01*
G01X121260Y16142D02*
X114961D01*
G01X103937Y7052D02*
G03Y12632I0J2790D01*
G01D02*
G03Y7052I0J-2790D01*
G01Y10671D02*
G03Y9013I0J-829D01*
G01D02*
G03Y10671I0J829D01*
G01X100788Y9842D02*
Y3543D01*
G01D02*
X107087D01*
G01D02*
Y9842D01*
G01X103937Y6693D02*
G03X107087Y9842I0J3150D01*
G01X100788D02*
G03X103937Y6693I3149J0D01*
G01X107087Y9842D02*
G03X103937Y12992I-3150J0D01*
G01X107087Y9842D02*
Y16142D01*
G01D02*
X100788D01*
G01D02*
Y9842D01*
G01X103937Y12992D02*
G03X100788Y9842I1J-3150D01*
G01X107087Y3543D02*
Y16142D01*
G01X100788Y3543D02*
X107087D01*
G01X100788Y16142D02*
Y3543D01*
G01X107087Y16142D02*
X100788D01*
G01X89764Y7052D02*
G03Y12632I0J2790D01*
G01D02*
G03Y7052I0J-2790D01*
G01Y10671D02*
G03Y9013I0J-829D01*
G01D02*
G03Y10671I0J829D01*
G01X86615Y9842D02*
Y3543D01*
G01D02*
X92914D01*
G01D02*
Y9842D01*
G01X89764Y6693D02*
G03X92914Y9842I0J3150D01*
G01X86615D02*
G03X89764Y6693I3149J0D01*
G01X92914Y9842D02*
G03X89764Y12992I-3150J0D01*
G01X92914Y9842D02*
Y16142D01*
G01D02*
X86615D01*
G01D02*
Y9842D01*
G01X89764Y12992D02*
G03X86615Y9842I0J-3149D01*
G01X92914Y3543D02*
Y16142D01*
G01X86615Y3543D02*
X92914D01*
G01X86615Y16142D02*
Y3543D01*
G01X92914Y16142D02*
X86615D01*
G01X75591Y7052D02*
G03Y12632I0J2790D01*
G01D02*
G03Y7052I0J-2790D01*
G01Y10671D02*
G03Y9013I0J-829D01*
G01D02*
G03Y10671I0J829D01*
G01X72441Y9842D02*
Y3543D01*
G01D02*
X78741D01*
G01D02*
Y9842D01*
G01X75591Y6693D02*
G03X78741Y9842I0J3150D01*
G01X72441D02*
G03X75591Y6693I3150J1D01*
G01X78741Y9842D02*
G03X75591Y12992I-3150J0D01*
G01X78741Y9842D02*
Y16142D01*
G01D02*
X72441D01*
G01D02*
Y9842D01*
G01X75591Y12992D02*
G03X72441Y9842I0J-3150D01*
G01X78741Y3543D02*
Y16142D01*
G01X72441Y3543D02*
X78741D01*
G01X72441Y16142D02*
Y3543D01*
G01X78741Y16142D02*
X72441D01*
G01X61418Y7052D02*
G03Y12632I0J2790D01*
G01D02*
G03Y7052I0J-2790D01*
G01Y10671D02*
G03Y9013I0J-829D01*
G01D02*
G03Y10671I0J829D01*
G01X58268Y9842D02*
Y3543D01*
G01D02*
X64567D01*
G01D02*
Y9842D01*
G01X61418Y6693D02*
G03X64567Y9842I0J3149D01*
G01X58268D02*
G03X61418Y6693I3150J1D01*
G01X64567Y9842D02*
G03X61418Y12992I-3150J0D01*
G01X64567Y9842D02*
Y16142D01*
G01D02*
X58268D01*
G01D02*
Y9842D01*
G01X61418Y12992D02*
G03X58268Y9842I0J-3150D01*
G01X64567Y3543D02*
Y16142D01*
G01X58268Y3543D02*
X64567D01*
G01X58268Y16142D02*
Y3543D01*
G01X64567Y16142D02*
X58268D01*
G01X47244Y7052D02*
G03Y12632I0J2790D01*
G01D02*
G03Y7052I0J-2790D01*
G01Y10671D02*
G03Y9013I0J-829D01*
G01D02*
G03Y10671I0J829D01*
G01X44095Y9842D02*
Y3543D01*
G01D02*
X50394D01*
G01D02*
Y9842D01*
G01X47244Y6693D02*
G03X50394Y9842I1J3149D01*
G01X44095D02*
G03X47244Y6693I3149J0D01*
G01X50394Y9842D02*
G03X47244Y12992I-3150J0D01*
G01X50394Y9842D02*
Y16142D01*
G01D02*
X44095D01*
G01D02*
Y9842D01*
G01X47244Y12992D02*
G03X44095Y9842I1J-3150D01*
G01X50394Y3543D02*
Y16142D01*
G01X44095Y3543D02*
X50394D01*
G01X44095Y16142D02*
Y3543D01*
G01X50394Y16142D02*
X44095D01*
G01X33342Y17716D02*
G03X33465Y19685I-15625J1964D01*
G01D02*
G03X33342Y21653I-15748J4D01*
G01X57008Y46949D02*
G03I-591J0D01*
G01X53839Y47736D02*
G03X53248Y48327I-591J0D01*
G01X53839Y47343D02*
G03X53051Y48130I-788J-1D01*
G01X54823Y47343D02*
G03X54035Y48130I-787J0D01*
G01X57402Y46949D02*
G03I-985J0D01*
G01X54823Y47736D02*
G03X53248Y49311I-1575J0D01*
G01X58071Y48130D02*
G03X54213Y51988I-3858J0D01*
G01X58661Y48130D02*
G03X54213Y52579I-4449J0D01*
G01X59252Y48130D02*
G03X54213Y53169I-5039J0D01*
G01X60394Y47933D02*
G03X54016Y54311I-6378J0D01*
G01X53248Y45571D02*
G03X53839Y46161I0J591D01*
G01X53051Y45768D02*
G03X53839Y46555I1J787D01*
G01X54035Y45768D02*
G03X54823Y46555I1J787D01*
G01X53248Y44587D02*
G03X54823Y46161I0J1575D01*
G01X54213Y41909D02*
G03X58071Y45768I0J3858D01*
G01X54213Y41319D02*
G03X58661Y45768I-1J4449D01*
G01X54213Y40728D02*
G03X59252Y45768I0J5039D01*
G01X54016Y39587D02*
G03X60394Y45965I0J6378D01*
G01X47362Y56004D02*
X35945D01*
G01X54016Y55906D02*
X47953D01*
G01X35945Y54968D02*
X47362D01*
G01X54016Y54921D02*
X47953D01*
G01X54016Y54843D02*
X47953D01*
G01X47362Y54823D02*
X35945D01*
G01X47362Y54564D02*
X35945D01*
G01X52087Y51594D02*
X52874D01*
G01X50118D02*
X50906D01*
G01X48150D02*
X48937D01*
G01X46181D02*
X46969D01*
G01X44213D02*
X45000D01*
G01X42244D02*
X43031D01*
G01X40276D02*
X41063D01*
G01X38307D02*
X39094D01*
G01X36339D02*
X37126D01*
G01X34370D02*
X35157D01*
G01X53266Y48130D02*
X53408Y48115D01*
X53545Y48070D01*
X53671Y47998D01*
X53783Y47899D01*
X53874Y47781D01*
X53941Y47645D01*
X53983Y47498D01*
X53997Y47343D01*
G01X52087Y49705D02*
X52874D01*
G01X50118D02*
X50906D01*
G01X48150D02*
X48937D01*
G01X46181D02*
X46969D01*
G01X44213D02*
X45000D01*
G01X42244D02*
X43031D01*
G01X40276D02*
X41063D01*
G01X38307D02*
X39094D01*
G01X36339D02*
X37126D01*
G01X34370D02*
X35157D01*
G01Y48839D02*
X34370D01*
G01X37126D02*
X36339D01*
G01X39094D02*
X38307D01*
G01X41063D02*
X40276D01*
G01X43031D02*
X42244D01*
G01X45000D02*
X44213D01*
G01X46969D02*
X46181D01*
G01X48937D02*
X48150D01*
G01X50906D02*
X50118D01*
G01X52874D02*
X52087D01*
G01X58661Y48130D02*
X58071D01*
G01X54823Y47736D02*
X53839D01*
G01Y46161D02*
X54823D01*
G01X58071Y45768D02*
X58661D01*
G01X35157Y45059D02*
X34370D01*
G01X37126D02*
X36339D01*
G01X39094D02*
X38307D01*
G01X41063D02*
X40276D01*
G01X43031D02*
X42244D01*
G01X45000D02*
X44213D01*
G01X46969D02*
X46181D01*
G01X48937D02*
X48150D01*
G01X50906D02*
X50118D01*
G01X52874D02*
X52087D01*
G01X54035Y45768D02*
X54178Y45783D01*
X54314Y45827D01*
X54440Y45899D01*
X54552Y45998D01*
X54643Y46117D01*
X54711Y46252D01*
X54752Y46400D01*
X54767Y46555D01*
G01X54035Y45768D02*
X54211Y45787D01*
X54377Y45846D01*
X54526Y45939D01*
X54651Y46064D01*
X54745Y46214D01*
X54803Y46380D01*
X54823Y46555D01*
G01X54035Y48130D02*
X54239Y48103D01*
X54429Y48024D01*
X54592Y47899D01*
X54718Y47736D01*
X54796Y47546D01*
X54823Y47343D01*
G01X52087Y44193D02*
X52874D01*
G01X50118D02*
X50906D01*
G01X48150D02*
X48937D01*
G01X46181D02*
X46969D01*
G01X44213D02*
X45000D01*
G01X42244D02*
X43031D01*
G01X40276D02*
X41063D01*
G01X38307D02*
X39094D01*
G01X36339D02*
X37126D01*
G01X34370D02*
X35157D01*
G01X52087Y42303D02*
X52874D01*
G01X50118D02*
X50906D01*
G01X48150D02*
X48937D01*
G01X46181D02*
X46969D01*
G01X44213D02*
X45000D01*
G01X42244D02*
X43031D01*
G01X40276D02*
X41063D01*
G01X38307D02*
X39094D01*
G01X36339D02*
X37126D01*
G01X34370D02*
X35157D01*
G01X35945Y39334D02*
X47362D01*
G01X35945Y39075D02*
X47362D01*
G01X54016Y39055D02*
X47953D01*
G01Y38976D02*
X54016D01*
G01X47362Y38930D02*
X35945D01*
G01X54016Y37992D02*
X47953D01*
G01X47362Y37894D02*
X35945D01*
G01X60394Y47933D02*
Y45965D01*
G01X59252Y48130D02*
Y45768D01*
G01X58661Y48130D02*
Y45768D01*
G01X53997Y46555D02*
X53983Y46402D01*
X53942Y46255D01*
X53875Y46119D01*
X53783Y45998D01*
X53673Y45901D01*
X53547Y45828D01*
X53411Y45783D01*
X53266Y45768D01*
G01X58071D02*
Y48130D01*
G01X54823Y47736D02*
Y46161D01*
G01X54767Y46555D02*
Y47343D01*
G01X54213Y41909D02*
Y41319D01*
G01Y52579D02*
Y51988D01*
G01X54154Y54309D02*
Y39588D01*
G01X54016Y54311D02*
Y55906D01*
G01Y37992D02*
Y39587D01*
G01X53997Y46555D02*
Y47343D01*
G01X53839Y47736D02*
Y46161D01*
G01X53760Y47185D02*
Y46713D01*
G01X53266Y45768D02*
Y48130D01*
G01X53248Y45571D02*
Y44587D01*
G01Y49311D02*
Y48327D01*
G01X53228Y54921D02*
Y55906D01*
G01Y37992D02*
Y38976D01*
G01X53169Y46713D02*
Y47185D01*
G01X52874Y45059D02*
Y42303D01*
G01Y51594D02*
Y48839D01*
G01X52677Y54921D02*
Y55906D01*
G01Y38976D02*
Y37992D01*
G01X52087Y45059D02*
Y42303D01*
G01Y51594D02*
Y48839D01*
G01X54767Y47343D02*
X54753Y47495D01*
X54711Y47643D01*
X54644Y47778D01*
X54552Y47899D01*
X54442Y47997D01*
X54317Y48069D01*
X54180Y48114D01*
X54035Y48130D01*
G01X51890Y54921D02*
Y55906D01*
G01Y38976D02*
Y37992D01*
G01X51791Y54921D02*
Y55906D01*
G01Y38976D02*
Y37992D01*
G01X51693Y54921D02*
Y55906D01*
G01Y37992D02*
Y38976D01*
G01X50906Y45059D02*
Y42303D01*
G01Y51594D02*
Y48839D01*
G01X50512Y54921D02*
Y55906D01*
G01Y37992D02*
Y38976D01*
G01X50413Y54921D02*
Y55906D01*
G01Y38976D02*
Y37992D01*
G01X50315Y54921D02*
Y55906D01*
G01Y38976D02*
Y37992D01*
G01X50118Y45059D02*
Y42303D01*
G01Y51594D02*
Y48839D01*
G01X49528Y54921D02*
Y55906D01*
G01Y38976D02*
Y37992D01*
G01X48937Y45059D02*
Y42303D01*
G01Y51594D02*
Y48839D01*
G01X48740Y38976D02*
Y37992D01*
G01Y55906D02*
Y54921D01*
G01X48150Y45059D02*
Y42303D01*
G01Y51594D02*
Y48839D01*
G01X47953Y39587D02*
Y37992D01*
G01Y55906D02*
Y54311D01*
G01X47362D02*
Y56004D01*
G01Y37894D02*
Y39587D01*
G01X46969Y45059D02*
Y42303D01*
G01Y51594D02*
Y48839D01*
G01X46772Y54823D02*
Y56004D01*
G01Y37894D02*
Y39075D01*
G01X46181Y45059D02*
Y42303D01*
G01Y51594D02*
Y48839D01*
G01X45984Y54823D02*
Y56004D01*
G01Y37894D02*
Y39075D01*
G01X45394Y54823D02*
Y56004D01*
G01Y37894D02*
Y39075D01*
G01X45000Y45059D02*
Y42303D01*
G01Y51594D02*
Y48839D01*
G01X44803Y54823D02*
Y56004D01*
G01Y37894D02*
Y39075D01*
G01X44213Y45059D02*
Y42303D01*
G01Y51594D02*
Y48839D01*
G01X43228Y54823D02*
Y56004D01*
G01Y37894D02*
Y39075D01*
G01X43031Y45059D02*
Y42303D01*
G01Y51594D02*
Y48839D01*
G01X42638Y54823D02*
Y56004D01*
G01Y37894D02*
Y39075D01*
G01X42244Y45059D02*
Y42303D01*
G01Y51594D02*
Y48839D01*
G01X42047Y39075D02*
Y37894D01*
G01Y56004D02*
Y54823D01*
G01X41260D02*
Y56004D01*
G01Y37894D02*
Y39075D01*
G01X41063Y45059D02*
Y42303D01*
G01Y51594D02*
Y48839D01*
G01X40669Y54823D02*
Y56004D01*
G01Y37894D02*
Y39075D01*
G01X40276Y45059D02*
Y42303D01*
G01Y51594D02*
Y48839D01*
G01X40079Y54823D02*
Y56004D01*
G01Y37894D02*
Y39075D01*
G01X39094Y45059D02*
Y42303D01*
G01Y51594D02*
Y48839D01*
G01X38504Y54823D02*
Y56004D01*
G01Y37894D02*
Y39075D01*
G01X38307Y45059D02*
Y42303D01*
G01Y51594D02*
Y48839D01*
G01X37913Y54823D02*
Y56004D01*
G01Y37894D02*
Y39075D01*
G01X37323D02*
Y37894D01*
G01Y56004D02*
Y54823D01*
G01X37126Y45059D02*
Y42303D01*
G01Y51594D02*
Y48839D01*
G01X36535Y39075D02*
Y37894D01*
G01Y56004D02*
Y54823D01*
G01X36339Y45059D02*
Y42303D01*
G01Y51594D02*
Y48839D01*
G01X35945Y39587D02*
Y37894D01*
G01Y56004D02*
Y54311D01*
G01X35354Y37992D02*
Y39587D01*
G01Y55906D02*
Y54311D01*
G01X35157Y45059D02*
Y42303D01*
G01Y51594D02*
Y48839D01*
G01X34567Y37992D02*
Y38976D01*
G01Y55906D02*
Y54921D01*
G01X34370Y45059D02*
Y42303D01*
G01Y51594D02*
Y48839D01*
G01X33780Y37992D02*
Y38976D01*
G01Y55906D02*
Y54921D01*
G01X106785Y47148D02*
X106417Y47711D01*
G01X106969Y48650D02*
X107704Y47899D01*
G01X106417Y47711D02*
X105866Y48087D01*
G01X106234Y49025D02*
X106969Y48650D01*
G01X105866Y48087D02*
X104948Y48274D01*
G01X105131Y49213D02*
X106234Y49025D01*
G01X91168Y44897D02*
X93740Y43583D01*
G01X104396Y49213D02*
X105131D01*
G01X96313D02*
X97415D01*
G01X87310D02*
X88412D01*
G01X81063D02*
X82165D01*
G01X104948Y48274D02*
X104213D01*
G01X102376Y47148D02*
X101457D01*
G01X82165Y45648D02*
X87310D01*
G01Y44522D02*
X82165D01*
G01X103110Y49025D02*
X104396Y49213D01*
G01X104213Y48274D02*
X103294Y48087D01*
G01X106785Y46773D02*
Y47148D01*
G01X93373Y46773D02*
X93740Y46210D01*
G01X93373Y43020D02*
X89882Y44897D01*
G01X102743Y41332D02*
X107887D01*
G01X98885D02*
X99803D01*
G01X82165Y40394D02*
X81063D01*
G01X88412D02*
X87310D01*
G01X97415D02*
X96313D01*
G01X99803D02*
X98885D01*
G01X107887D02*
X101273D01*
G01X107704Y46023D02*
X107336Y45460D01*
G01X106417Y46023D02*
X106785Y46773D01*
G01X101457Y47148D02*
X101641Y47899D01*
G01X101273Y40394D02*
Y41332D01*
G01X99803D02*
Y40394D01*
G01X98885D02*
Y41332D01*
G01X97415Y49213D02*
Y40394D01*
G01X96313D02*
Y47711D01*
G01X107336Y45460D02*
X102743Y41332D01*
G01X101273D02*
X106417Y46023D01*
G01X102743Y47711D02*
X102376Y47148D01*
G01X95210Y46398D02*
Y47899D01*
G01X101641D02*
X102376Y48650D01*
G01X96313Y47711D02*
X95210Y46398D01*
G01X93740Y43583D02*
X93373Y43020D01*
G01X88412Y49213D02*
Y40394D01*
G01X87310Y45648D02*
Y49213D01*
G01Y40394D02*
Y44522D01*
G01X102376Y48650D02*
X103110Y49025D01*
G01X93740Y46210D02*
X91168Y44897D01*
G01X103294Y48087D02*
X102743Y47711D01*
G01X95210Y47899D02*
X96313Y49213D01*
G01X82165Y44522D02*
Y40394D01*
G01Y49213D02*
Y45648D01*
G01X81063Y40394D02*
Y49213D01*
G01X89882Y44897D02*
X93373Y46773D01*
G01X114869Y43959D02*
X115053Y43396D01*
G01X115971Y43583D02*
X115604Y44522D01*
G01X114502D02*
X114869Y43959D01*
G01X115604Y44522D02*
X115053Y45272D01*
G01D02*
X114134Y45835D01*
G01X115971Y42833D02*
Y43583D01*
G01X115604Y48274D02*
Y49213D01*
G01X115053Y43396D02*
Y43020D01*
G01X107704Y47899D02*
X107887Y47148D01*
G01X110827Y41895D02*
X110459Y42645D01*
G01X109357D02*
X109724Y41895D01*
G01D02*
X110276Y41144D01*
G01X113950Y44897D02*
X114502Y44522D01*
G01X111378Y41519D02*
X110827Y41895D01*
G01X110276Y41144D02*
X111194Y40581D01*
G01X113215Y45085D02*
X113950Y44897D01*
G01X114134Y45835D02*
X113215Y46023D01*
G01X115604Y41895D02*
X115971Y42833D01*
G01X115053Y43020D02*
X114869Y42457D01*
G01X110276Y45272D02*
Y48274D01*
G01X109357Y49213D02*
Y44334D01*
G01X112113Y41332D02*
X111378Y41519D01*
G01X111194Y40581D02*
X112113Y40394D01*
G01X115604Y49213D02*
X109357D01*
G01X110276Y48274D02*
X115604D01*
G01X113215Y46023D02*
X112113D01*
G01Y45085D02*
X113215D01*
G01X109357Y44334D02*
X110643D01*
G01X115053Y41144D02*
X115604Y41895D01*
G01X114869Y42457D02*
X114502Y41895D01*
G01X107887Y46773D02*
X107704Y46023D01*
G01X107887Y41332D02*
Y40394D01*
G01Y47148D02*
Y46773D01*
G01X110459Y42645D02*
X109357D01*
G01X113215Y41332D02*
X112113D01*
G01Y40394D02*
X113215D01*
G01X112113Y46023D02*
X111194Y45835D01*
G01X111378Y44897D02*
X112113Y45085D01*
G01X113215Y40394D02*
X114134Y40581D01*
G01X113950Y41519D02*
X113215Y41332D01*
G01X114134Y40581D02*
X115053Y41144D01*
G01X114502Y41895D02*
X113950Y41519D01*
G01X110643Y44334D02*
X111378Y44897D01*
G01X111194Y45835D02*
X110276Y45272D01*
G01X124807Y-381883D02*
Y-399206D01*
G01X189564Y-19685D02*
X539370D01*
G01X185627D02*
X186119D01*
G01X196851Y-7874D02*
G03Y0I0J3937D01*
G01X185627Y-19685D02*
Y-20079D01*
G01Y-19685D02*
Y-19292D01*
G01X185135Y-19685D02*
X186119D01*
G01X189564D02*
G03X181690I-3937J0D01*
G01X165355Y-7874D02*
X196851D01*
G01X165355Y0D02*
G03Y-7874I0J-3937D01*
G01X140158D02*
G03Y0I0J3937D01*
G01X185040Y18307D02*
G03X177166I-3937J0D01*
G01X211024Y19685D02*
G03X194489I-8267J0D01*
G01D02*
G03X211024I8267J0D01*
G01D02*
G03X194489I-8267J0D01*
G01D02*
G03X211024I8267J0D01*
G01D02*
G03X194489I-8267J0D01*
G01D02*
G03X211024I8267J0D01*
G01D02*
G03X194489I-8267J0D01*
G01D02*
G03X211024I8267J0D01*
G01X194489D02*
G03X211024I8267J0D01*
G01D02*
G03X194489I-8267J0D01*
G01D02*
G03X211024I8267J0D01*
G01D02*
G03X194489I-8267J0D01*
G01X188977Y0D02*
X358268D01*
G01X185040Y3937D02*
G03X188977Y0I3937J0D01*
G01X185040Y57874D02*
Y3937D01*
G01X116929Y5413D02*
Y5708D01*
G01D02*
X119292D01*
G01D02*
Y5413D01*
G01D02*
X118136D01*
G01D02*
X119292Y4330D01*
G01D02*
Y3937D01*
G01D02*
X118337Y4823D01*
G01D02*
X116929Y3937D01*
G01D02*
Y4330D01*
G01D02*
X118085Y5069D01*
G01D02*
X117734Y5413D01*
G01D02*
X116929D01*
G01X117734Y15206D02*
X119091Y14764D01*
G01X117734Y14321D02*
Y15206D01*
G01X119091Y14764D02*
X117734Y14321D01*
G01X119292Y14567D02*
X116929Y13779D01*
G01D02*
Y14075D01*
G01D02*
X117533Y14271D01*
G01D02*
Y15256D01*
G01D02*
X116929Y15453D01*
G01D02*
Y15748D01*
G01D02*
X119292Y14960D01*
G01D02*
Y14567D01*
G01X164080Y28701D02*
X163699D01*
G01D02*
Y31193D01*
G01D02*
X164080D01*
G01D02*
Y30960D01*
G01D02*
X164233Y31116D01*
G01D02*
X164462Y31193D01*
G01D02*
X164767D01*
G01D02*
X164996Y31116D01*
G01D02*
X165224Y30882D01*
G01D02*
X165453Y31116D01*
G01D02*
X165682Y31193D01*
G01D02*
X165987D01*
G01D02*
X166216Y31116D01*
G01D02*
X166368Y30960D01*
G01D02*
X166521Y30570D01*
G01D02*
Y28701D01*
G01D02*
X166140D01*
G01D02*
Y30570D01*
G01D02*
X166063Y30726D01*
G01D02*
X165987Y30804D01*
G01D02*
X165835Y30882D01*
G01D02*
X165606D01*
G01D02*
X165453Y30804D01*
G01D02*
X165377Y30726D01*
G01D02*
X165301Y30570D01*
G01D02*
Y28701D01*
G01D02*
X164919D01*
G01D02*
Y30570D01*
G01D02*
X164843Y30726D01*
G01D02*
X164767Y30804D01*
G01D02*
X164614Y30882D01*
G01D02*
X164462D01*
G01D02*
X164233Y30804D01*
G01D02*
X164080Y30648D01*
G01D02*
Y28701D01*
G01X160648D02*
X160266D01*
G01D02*
Y31193D01*
G01D02*
X160648D01*
G01D02*
Y30960D01*
G01D02*
X160800Y31116D01*
G01D02*
X161029Y31193D01*
G01D02*
X161334D01*
G01D02*
X161563Y31116D01*
G01D02*
X161792Y30882D01*
G01D02*
X162021Y31116D01*
G01D02*
X162250Y31193D01*
G01D02*
X162555D01*
G01D02*
X162783Y31116D01*
G01D02*
X162936Y30960D01*
G01D02*
X163089Y30570D01*
G01D02*
Y28701D01*
G01D02*
X162707D01*
G01D02*
Y30570D01*
G01D02*
X162631Y30726D01*
G01D02*
X162555Y30804D01*
G01D02*
X162402Y30882D01*
G01D02*
X162173D01*
G01D02*
X162021Y30804D01*
G01D02*
X161944Y30726D01*
G01D02*
X161868Y30570D01*
G01D02*
Y28701D01*
G01D02*
X161487D01*
G01D02*
Y30570D01*
G01D02*
X161411Y30726D01*
G01D02*
X161334Y30804D01*
G01D02*
X161181Y30882D01*
G01D02*
X161029D01*
G01D02*
X160800Y30804D01*
G01D02*
X160648Y30648D01*
G01D02*
Y28701D01*
G01X157291Y30804D02*
Y30258D01*
G01D02*
X157368Y29791D01*
G01D02*
X157673Y29324D01*
G01D02*
X157902Y29168D01*
G01D02*
X158283Y29090D01*
G01D02*
X158665Y29168D01*
G01D02*
X158893Y29324D01*
G01D02*
X159198Y29791D01*
G01D02*
X159275Y30258D01*
G01D02*
Y30804D01*
G01D02*
X159198Y31271D01*
G01D02*
X158893Y31739D01*
G01X157673D02*
X157368Y31271D01*
G01D02*
X157291Y30804D01*
G01X156986Y31271D02*
X156910Y30882D01*
G01X157063Y31505D02*
X156986Y31271D01*
G01X157215Y31817D02*
X157063Y31505D01*
G01X159503D02*
X159351Y31817D01*
G01X159580Y31271D02*
X159503Y31505D01*
G01X159656Y30882D02*
X159580Y31271D01*
G01X159656Y30180D02*
Y30882D01*
G01X159580Y29791D02*
X159656Y30180D01*
G01X159503Y29557D02*
X159580Y29791D01*
G01X159351Y29246D02*
X159503Y29557D01*
G01X159122Y29012D02*
X159351Y29246D01*
G01X158741Y28778D02*
X159122Y29012D01*
G01X158283Y28701D02*
X158741Y28778D01*
G01X157825D02*
X158283Y28701D01*
G01X157444Y29012D02*
X157825Y28778D01*
G01X157215Y29246D02*
X157444Y29012D01*
G01X157063Y29557D02*
X157215Y29246D01*
G01X156986Y29791D02*
X157063Y29557D01*
G01X156910Y30180D02*
X156986Y29791D01*
G01X156910Y30882D02*
Y30180D01*
G01X155079Y30258D02*
X156300D01*
G01D02*
Y29947D01*
G01D02*
X155079D01*
G01D02*
Y30258D01*
G01Y31193D02*
X156300D01*
G01D02*
Y30882D01*
G01D02*
X155079D01*
G01D02*
Y31193D01*
G01X151876Y28701D02*
X151418D01*
G01D02*
Y32362D01*
G01X151876D02*
Y30882D01*
G01D02*
X154011D01*
G01D02*
Y32362D01*
G01X154469D02*
Y28701D01*
G01D02*
X154011D01*
G01D02*
Y30414D01*
G01D02*
X151876D01*
G01D02*
Y28701D01*
G01X118111Y7052D02*
G03Y12632I0J2790D01*
G01Y10671D02*
G03Y9013I0J-829D01*
G01D02*
G03Y10671I0J829D01*
G01X121260Y3543D02*
Y9842D01*
G01X118111Y6693D02*
G03X121260Y9842I0J3149D01*
G01D02*
G03X118111Y12992I-3150J0D01*
G01X121260Y9842D02*
Y16142D01*
G01Y3543D02*
Y16142D01*
G01X175074Y17716D02*
X169093D01*
G01X161418Y10041D02*
G03X169093Y17716I-1969J9644D01*
G01X161418Y10041D02*
Y4060D01*
G01X157481D02*
Y10041D01*
G01X149805Y17716D02*
G03X157481Y10041I9644J1969D01*
G01X149805Y17716D02*
X143825D01*
G01Y21653D02*
X149805D01*
G01X157481Y29329D02*
G03X149805Y21653I1968J-9644D01*
G01X157481Y29329D02*
Y35309D01*
G01X161418D02*
Y29329D01*
G01X169093Y21653D02*
G03X161418Y29329I-9644J-1968D01*
G01X169093Y21653D02*
X175074D01*
G01X149607Y19685D02*
G03X169292I9842J0D01*
G01D02*
G03X149607I-9843J0D01*
G01X157481Y4060D02*
G03X161418I1968J15625D01*
G01X175074Y17716D02*
G03X175197Y19685I-15625J1964D01*
G01X143701D02*
G03X143825Y17716I15748J3D01*
G01Y21653D02*
G03X143701Y19685I15624J-1972D01*
G01X175197D02*
G03X175074Y21653I-15748J4D01*
G01X167717Y19685D02*
G03X151181I-8268J0D01*
G01D02*
G03X167717I8268J0D01*
G01X161418Y10041D02*
G03X169093Y17716I-1969J9644D01*
G01X175074D02*
X169093D01*
G01X161418Y4060D02*
G03X175074Y17716I-1969J15625D01*
G01X161418Y10041D02*
Y4060D01*
G01X149805Y17716D02*
G03X157481Y10041I9644J1969D01*
G01Y4060D02*
Y10041D01*
G01X143825Y17716D02*
G03X157481Y4060I15625J1969D01*
G01X149805Y17716D02*
X143825D01*
G01X157481Y29329D02*
G03X149805Y21653I1968J-9644D01*
G01X143825D02*
X149805D01*
G01X157481Y35309D02*
G03X143825Y21653I1968J-15624D01*
G01X157481Y29329D02*
Y35309D01*
G01X175074Y21653D02*
G03X161418Y35309I-15625J-1969D01*
G01X169093Y21653D02*
X175074D01*
G01X169093D02*
G03X161418Y29329I-9644J-1968D01*
G01Y35309D02*
Y29329D01*
G01X169546Y13287D02*
G03X171515I985J0D01*
G01D02*
G03X169546I-985J0D01*
G01X164863Y8604D02*
G03X166831I984J0D01*
G01D02*
G03X164863I-984J0D01*
G01X147384Y13287D02*
G03X149353I984J0D01*
G01D02*
G03X147384I-985J0D01*
G01X152067Y8604D02*
G03X154036I984J0D01*
G01D02*
G03X152067I-984J0D01*
G01X169546Y26082D02*
G03X171515I985J0D01*
G01D02*
G03X169546I-985J0D01*
G01X164863Y30766D02*
G03X166831I984J0D01*
G01D02*
G03X164863I-984J0D01*
G01X147384Y26082D02*
G03X149353I984J0D01*
G01D02*
G03X147384I-985J0D01*
G01X152067Y30766D02*
G03X154036I984J0D01*
G01D02*
G03X152067I-984J0D01*
G01X169546Y13287D02*
G03X171515I985J0D01*
G01D02*
G03X169546I-985J0D01*
G01X164863Y8604D02*
G03X166831I984J0D01*
G01D02*
G03X164863I-984J0D01*
G01X147384Y13287D02*
G03X149353I984J0D01*
G01D02*
G03X147384I-985J0D01*
G01X152067Y8604D02*
G03X154036I984J0D01*
G01D02*
G03X152067I-984J0D01*
G01X169546Y26082D02*
G03X171515I985J0D01*
G01D02*
G03X169546I-985J0D01*
G01X164863Y30766D02*
G03X166831I984J0D01*
G01D02*
G03X164863I-984J0D01*
G01X147384Y26082D02*
G03X149353I984J0D01*
G01D02*
G03X147384I-985J0D01*
G01X152067Y30766D02*
G03X154036I984J0D01*
G01D02*
G03X152067I-984J0D01*
G01X167717Y19685D02*
G03X151181I-8268J0D01*
G01D02*
G03X167717I8268J0D01*
G01D02*
G03X151181I-8268J0D01*
G01D02*
G03X167717I8268J0D01*
G01X169546Y13287D02*
G03X171515I985J0D01*
G01D02*
G03X169546I-985J0D01*
G01X164863Y8604D02*
G03X166831I984J0D01*
G01D02*
G03X164863I-984J0D01*
G01X147384Y13287D02*
G03X149353I984J0D01*
G01D02*
G03X147384I-985J0D01*
G01X152067Y8604D02*
G03X154036I984J0D01*
G01D02*
G03X152067I-984J0D01*
G01X169546Y26082D02*
G03X171515I985J0D01*
G01D02*
G03X169546I-985J0D01*
G01X164863Y30766D02*
G03X166831I984J0D01*
G01D02*
G03X164863I-984J0D01*
G01X147384Y26082D02*
G03X149353I984J0D01*
G01D02*
G03X147384I-985J0D01*
G01X152067Y30766D02*
G03X154036I984J0D01*
G01D02*
G03X152067I-984J0D01*
G01X149607Y19685D02*
G03X169292I9842J0D01*
G01D02*
G03X149607I-9843J0D01*
G01X169546Y13287D02*
G03X171515I985J0D01*
G01D02*
G03X169546I-985J0D01*
G01X164863Y8604D02*
G03X166831I984J0D01*
G01D02*
G03X164863I-984J0D01*
G01X147384Y13287D02*
G03X149353I984J0D01*
G01D02*
G03X147384I-985J0D01*
G01X152067Y8604D02*
G03X154036I984J0D01*
G01D02*
G03X152067I-984J0D01*
G01X169546Y26082D02*
G03X171515I985J0D01*
G01D02*
G03X169546I-985J0D01*
G01X164863Y30766D02*
G03X166831I984J0D01*
G01D02*
G03X164863I-984J0D01*
G01X147384Y26082D02*
G03X149353I984J0D01*
G01D02*
G03X147384I-985J0D01*
G01X152067Y30766D02*
G03X154036I984J0D01*
G01D02*
G03X152067I-984J0D01*
G01X167717Y19685D02*
G03X151181I-8268J0D01*
G01D02*
G03X167717I8268J0D01*
G01X151181D02*
G03X167717I8268J0D01*
G01D02*
G03X151181I-8268J0D01*
G01D02*
G03X167717I8268J0D01*
G01D02*
G03X151181I-8268J0D01*
G01X177166Y3937D02*
Y57874D01*
G01X173229Y0D02*
G03X177166Y3937I0J3937D01*
G01X132139Y45835D02*
X132507Y44897D01*
G01X131588D02*
X131404Y45272D01*
G01X128648Y44897D02*
X128465Y45272D01*
G01X131772Y46210D02*
X132139Y45835D01*
G01X131404Y45272D02*
X131220Y45460D01*
G01X128832Y46210D02*
X129383Y45648D01*
G01X128465Y45272D02*
X128281Y45460D01*
G01X132507Y44897D02*
Y40394D01*
G01X131588D02*
Y44897D01*
G01X129567D02*
Y40394D01*
G01X128648D02*
Y44897D01*
G01X123872Y45835D02*
X124239Y44897D01*
G01X123320D02*
X123137Y45272D01*
G01X120381Y44897D02*
X120197Y45272D01*
G01X123504Y46210D02*
X123872Y45835D01*
G01X123137Y45272D02*
X122953Y45460D01*
G01X120565Y46210D02*
X121116Y45648D01*
G01X120197Y45272D02*
X120013Y45460D01*
G01X131220D02*
X130853Y45648D01*
G01X126628Y45085D02*
Y40394D01*
G01Y46398D02*
Y45835D01*
G01X125709Y40394D02*
Y46398D01*
G01X124239Y44897D02*
Y40394D01*
G01X123320D02*
Y44897D01*
G01X121299D02*
Y40394D01*
G01X128281Y45460D02*
X127913Y45648D01*
G01X122953Y45460D02*
X122585Y45648D01*
G01X120013Y45460D02*
X119646Y45648D01*
G01X131220Y46398D02*
X131772Y46210D01*
G01X128281Y46398D02*
X128832Y46210D01*
G01X129751Y45272D02*
X129567Y44897D01*
G01X120381Y40394D02*
Y44897D01*
G01X118360Y45085D02*
Y40394D01*
G01Y46398D02*
Y45835D01*
G01X117441Y40394D02*
Y46398D01*
G01X122953D02*
X123504Y46210D01*
G01X120013Y46398D02*
X120565Y46210D01*
G01X121483Y45272D02*
X121299Y44897D01*
G01X130486Y46398D02*
X131220D01*
G01X127546D02*
X128281D01*
G01X125709D02*
X126628D01*
G01X122218D02*
X122953D01*
G01X119278D02*
X120013D01*
G01X117441D02*
X118360D01*
G01X119646Y45648D02*
X119278D01*
G01X122585D02*
X122034D01*
G01X127913D02*
X127546D01*
G01X130853D02*
X130302D01*
G01X129935Y45460D02*
X129751Y45272D01*
G01X129383Y45648D02*
X129935Y46210D01*
G01X126995Y45460D02*
X126628Y45085D01*
G01Y45835D02*
X126995Y46210D01*
G01X121667Y45460D02*
X121483Y45272D01*
G01X118360Y40394D02*
X117441D01*
G01X121299D02*
X120381D01*
G01X124239D02*
X123320D01*
G01X126628D02*
X125709D01*
G01X129567D02*
X128648D01*
G01X132507D02*
X131588D01*
G01X121116Y45648D02*
X121667Y46210D01*
G01X118727Y45460D02*
X118360Y45085D01*
G01Y45835D02*
X118727Y46210D01*
G01X130302Y45648D02*
X129935Y45460D01*
G01X122034Y45648D02*
X121667Y45460D01*
G01X129935Y46210D02*
X130486Y46398D01*
G01X127546Y45648D02*
X126995Y45460D01*
G01Y46210D02*
X127546Y46398D01*
G01X121667Y46210D02*
X122218Y46398D01*
G01X119278Y45648D02*
X118727Y45460D01*
G01Y46210D02*
X119278Y46398D01*
G01X185040Y87992D02*
G03X177166I-3937J0D01*
G01Y113189D02*
G03X185040I3937J0D01*
G01X196851Y61811D02*
G03Y69685I0J3937D01*
G01X165355D02*
G03Y61811I0J-3937D01*
G01X140158D02*
G03Y69685I0J3937D01*
G01X177166Y43504D02*
G03X185040I3937J0D01*
G01X167717Y89370D02*
G03X151181I-8268J0D01*
G01D02*
G03X167717I8268J0D01*
G01D02*
G03X151181I-8268J0D01*
G01D02*
G03X167717I8268J0D01*
G01D02*
G03X151181I-8268J0D01*
G01D02*
G03X167717I8268J0D01*
G01D02*
G03X151181I-8268J0D01*
G01D02*
G03X167717I8268J0D01*
G01X151181D02*
G03X167717I8268J0D01*
G01D02*
G03X151181I-8268J0D01*
G01D02*
G03X167717I8268J0D01*
G01D02*
G03X151181I-8268J0D01*
G01X177166Y73622D02*
Y127559D01*
G01X173229Y69685D02*
G03X177166Y73622I0J3937D01*
G01X211024Y89370D02*
G03X194489I-8267J0D01*
G01D02*
G03X211024I8267J0D01*
G01D02*
G03X194489I-8267J0D01*
G01D02*
G03X211024I8267J0D01*
G01D02*
G03X194489I-8267J0D01*
G01D02*
G03X211024I8267J0D01*
G01D02*
G03X194489I-8267J0D01*
G01D02*
G03X211024I8267J0D01*
G01X194489D02*
G03X211024I8267J0D01*
G01D02*
G03X194489I-8267J0D01*
G01D02*
G03X211024I8267J0D01*
G01D02*
G03X194489I-8267J0D01*
G01X188977Y69685D02*
X358268D01*
G01X185040Y73622D02*
G03X188977Y69685I3937J0D01*
G01X185040Y127559D02*
Y73622D01*
G01X188977Y61811D02*
G03X185040Y57874I0J-3937D01*
G01X358268Y61811D02*
X188977D01*
G01X158893Y31739D02*
X158665Y31894D01*
G01D02*
X158283Y31972D01*
G01D02*
X157902Y31894D01*
G01D02*
X157673Y31739D01*
G01X157444Y32050D02*
X157215Y31817D01*
G01X157825Y32284D02*
X157444Y32050D01*
G01X158283Y32362D02*
X157825Y32284D01*
G01X158741D02*
X158283Y32362D01*
G01X159122Y32050D02*
X158741Y32284D01*
G01X159351Y31817D02*
X159122Y32050D01*
G01X151418Y32362D02*
X151876D01*
G01X154011D02*
X154469D01*
G01X161418Y35309D02*
G03X157481I-1969J-15624D01*
G01X177166Y57874D02*
G03X173229Y61811I-3937J0D01*
G01X151181Y51937D02*
G03Y55937I0J2000D01*
G01D02*
G03Y51937I0J-2000D01*
G01X157481Y50037D02*
X144881D01*
G01X157481Y57837D02*
Y50037D01*
G01X144881Y57837D02*
X157481D01*
G01X144881Y50037D02*
Y57837D01*
G01X158581Y48937D02*
X143781D01*
G01X158581Y58937D02*
Y48937D01*
G01X143781Y58937D02*
X158581D01*
G01X143781Y48937D02*
Y58937D01*
G01X185040Y157677D02*
G03X177166I-3937J0D01*
G01Y182874D02*
G03X185040I3937J0D01*
G01X196851Y131496D02*
G03Y139370I0J3937D01*
G01X165355D02*
G03Y131496I0J-3937D01*
G01X140158D02*
G03Y139370I0J3937D01*
G01X151181Y191307D02*
G03Y195307I0J2000D01*
G01D02*
G03Y191307I0J-2000D01*
G01X157481Y189407D02*
X144881D01*
G01X157481Y197207D02*
Y189407D01*
G01X144881D02*
Y197207D01*
G01X158581Y188307D02*
X143781D01*
G01X158581Y198307D02*
Y188307D01*
G01X143781D02*
Y198307D01*
G01X151181Y121622D02*
G03Y125622I0J2000D01*
G01D02*
G03Y121622I0J-2000D01*
G01X157481Y119722D02*
X144881D01*
G01X157481Y127522D02*
Y119722D01*
G01X144881Y127522D02*
X157481D01*
G01X144881Y119722D02*
Y127522D01*
G01X158581Y118622D02*
X143781D01*
G01X158581Y128622D02*
Y118622D01*
G01X143781Y128622D02*
X158581D01*
G01X143781Y118622D02*
Y128622D01*
G01X167717Y159055D02*
G03X151181I-8268J0D01*
G01D02*
G03X167717I8268J0D01*
G01D02*
G03X151181I-8268J0D01*
G01D02*
G03X167717I8268J0D01*
G01D02*
G03X151181I-8268J0D01*
G01D02*
G03X167717I8268J0D01*
G01D02*
G03X151181I-8268J0D01*
G01D02*
G03X167717I8268J0D01*
G01X151181D02*
G03X167717I8268J0D01*
G01D02*
G03X151181I-8268J0D01*
G01D02*
G03X167717I8268J0D01*
G01D02*
G03X151181I-8268J0D01*
G01X177166Y143307D02*
Y197244D01*
G01X173229Y139370D02*
G03X177166Y143307I0J3937D01*
G01Y127559D02*
G03X173229Y131496I-3937J0D01*
G01X211024Y159055D02*
G03X194489I-8267J0D01*
G01D02*
G03X211024I8267J0D01*
G01D02*
G03X194489I-8267J0D01*
G01D02*
G03X211024I8267J0D01*
G01D02*
G03X194489I-8267J0D01*
G01D02*
G03X211024I8267J0D01*
G01D02*
G03X194489I-8267J0D01*
G01D02*
G03X211024I8267J0D01*
G01X194489D02*
G03X211024I8267J0D01*
G01D02*
G03X194489I-8267J0D01*
G01D02*
G03X211024I8267J0D01*
G01D02*
G03X194489I-8267J0D01*
G01X188977Y139370D02*
X358268D01*
G01X185040Y143307D02*
G03X188977Y139370I3937J0D01*
G01X185040Y197244D02*
Y143307D01*
G01X188977Y131496D02*
G03X185040Y127559I0J-3937D01*
G01X358268Y131496D02*
X188977D01*
G01X185040Y227362D02*
G03X177166I-3937J0D01*
G01Y252559D02*
G03X185040I3937J0D01*
G01X196851Y270866D02*
G03Y278740I0J3937D01*
G01X165355D02*
G03Y270866I0J-3937D01*
G01X140158D02*
G03Y278740I0J3937D01*
G01X196851Y201181D02*
G03Y209055I0J3937D01*
G01X165355D02*
G03Y201181I0J-3937D01*
G01X140158D02*
G03Y209055I0J3937D01*
G01X151181Y260992D02*
G03Y264992I0J2000D01*
G01D02*
G03Y260992I0J-2000D01*
G01X157481Y259092D02*
X144881D01*
G01X157481Y266892D02*
Y259092D01*
G01X144881Y266892D02*
X157481D01*
G01X144881Y259092D02*
Y266892D01*
G01X158581Y257992D02*
X143781D01*
G01X158581Y267992D02*
Y257992D01*
G01X143781Y267992D02*
X158581D01*
G01X143781Y257992D02*
Y267992D01*
G01X144881Y197207D02*
X157481D01*
G01X143781Y198307D02*
X158581D01*
G01X173229Y278740D02*
G03X177166Y282677I0J3937D01*
G01X188977Y278740D02*
X358268D01*
G01X185040Y282677D02*
G03X188977Y278740I3937J0D01*
G01X167717Y228740D02*
G03X151181I-8268J0D01*
G01D02*
G03X167717I8268J0D01*
G01D02*
G03X151181I-8268J0D01*
G01D02*
G03X167717I8268J0D01*
G01D02*
G03X151181I-8268J0D01*
G01D02*
G03X167717I8268J0D01*
G01D02*
G03X151181I-8268J0D01*
G01D02*
G03X167717I8268J0D01*
G01X151181D02*
G03X167717I8268J0D01*
G01D02*
G03X151181I-8268J0D01*
G01D02*
G03X167717I8268J0D01*
G01D02*
G03X151181I-8268J0D01*
G01X177166Y212992D02*
Y266929D01*
G01X173229Y209055D02*
G03X177166Y212992I0J3937D01*
G01Y266929D02*
G03X173229Y270866I-3937J0D01*
G01X211024Y228740D02*
G03X194489I-8267J0D01*
G01D02*
G03X211024I8267J0D01*
G01D02*
G03X194489I-8267J0D01*
G01D02*
G03X211024I8267J0D01*
G01D02*
G03X194489I-8267J0D01*
G01D02*
G03X211024I8267J0D01*
G01D02*
G03X194489I-8267J0D01*
G01D02*
G03X211024I8267J0D01*
G01X194489D02*
G03X211024I8267J0D01*
G01D02*
G03X194489I-8267J0D01*
G01D02*
G03X211024I8267J0D01*
G01D02*
G03X194489I-8267J0D01*
G01X188977Y209055D02*
X358268D01*
G01X185040Y212992D02*
G03X188977Y209055I3937J0D01*
G01X185040Y266929D02*
Y212992D01*
G01X188977Y270866D02*
G03X185040Y266929I0J-3937D01*
G01X358268Y270866D02*
X188977D01*
G01X177166Y197244D02*
G03X173229Y201181I-3937J0D01*
G01X188977D02*
G03X185040Y197244I0J-3937D01*
G01X358268Y201181D02*
X188977D01*
G01X185040Y297047D02*
G03X177166I-3937J0D01*
G01Y322244D02*
G03X185040I3937J0D01*
G01X196851Y340551D02*
G03Y348425I0J3937D01*
G01X165355D02*
G03Y340551I0J-3937D01*
G01X140158D02*
G03Y348425I0J3937D01*
G01X151181Y330677D02*
G03Y334677I0J2000D01*
G01D02*
G03Y330677I0J-2000D01*
G01X157481Y328777D02*
X144881D01*
G01X157481Y336577D02*
Y328777D01*
G01X144881Y336577D02*
X157481D01*
G01X144881Y328777D02*
Y336577D01*
G01X158581Y327677D02*
X143781D01*
G01X158581Y337677D02*
Y327677D01*
G01X143781Y337677D02*
X158581D01*
G01X143781Y327677D02*
Y337677D01*
G01X151181Y368110D02*
G03X167717I8268J0D01*
G01X151181D02*
G03X167717I8268J0D01*
G01X151181D02*
G03X167717I8268J0D01*
G01X151181D02*
G03X167717I8268J0D01*
G01X151181D02*
G03X167717I8268J0D01*
G01X151181D02*
G03X167717I8268J0D01*
G01X177166Y352362D02*
Y406299D01*
G01X173229Y348425D02*
G03X177166Y352362I0J3937D01*
G01X194489Y368110D02*
G03X211024I8267J0D01*
G01X194489D02*
G03X211024I8267J0D01*
G01X194489D02*
G03X211024I8267J0D01*
G01X194489D02*
G03X211024I8267J0D01*
G01X194489D02*
G03X211024I8267J0D01*
G01X194489D02*
G03X211024I8267J0D01*
G01X188977Y348425D02*
X358268D01*
G01X185040Y352362D02*
G03X188977Y348425I3937J0D01*
G01X185040Y406299D02*
Y352362D01*
G01X167717Y298425D02*
G03X151181I-8268J0D01*
G01D02*
G03X167717I8268J0D01*
G01D02*
G03X151181I-8268J0D01*
G01D02*
G03X167717I8268J0D01*
G01D02*
G03X151181I-8268J0D01*
G01D02*
G03X167717I8268J0D01*
G01D02*
G03X151181I-8268J0D01*
G01D02*
G03X167717I8268J0D01*
G01X151181D02*
G03X167717I8268J0D01*
G01D02*
G03X151181I-8268J0D01*
G01D02*
G03X167717I8268J0D01*
G01D02*
G03X151181I-8268J0D01*
G01X177166Y282677D02*
Y336614D01*
G01D02*
G03X173229Y340551I-3937J0D01*
G01X211024Y298425D02*
G03X194489I-8267J0D01*
G01D02*
G03X211024I8267J0D01*
G01D02*
G03X194489I-8267J0D01*
G01D02*
G03X211024I8267J0D01*
G01D02*
G03X194489I-8267J0D01*
G01D02*
G03X211024I8267J0D01*
G01D02*
G03X194489I-8267J0D01*
G01D02*
G03X211024I8267J0D01*
G01X194489D02*
G03X211024I8267J0D01*
G01D02*
G03X194489I-8267J0D01*
G01D02*
G03X211024I8267J0D01*
G01D02*
G03X194489I-8267J0D01*
G01X185040Y336614D02*
Y282677D01*
G01X188977Y340551D02*
G03X185040Y336614I0J-3937D01*
G01X358268Y340551D02*
X188977D01*
G01X185040Y436417D02*
G03X177166I-3937J0D01*
G01X185040Y366732D02*
G03X177166I-3937J0D01*
G01Y391929D02*
G03X185040I3937J0D01*
G01X196851Y410236D02*
G03Y418110I0J3937D01*
G01X165355D02*
G03Y410236I0J-3937D01*
G01X140158D02*
G03Y418110I0J3937D01*
G01X151181Y400362D02*
G03Y404362I0J2000D01*
G01D02*
G03Y400362I0J-2000D01*
G01X157481Y398462D02*
X144881D01*
G01X157481Y406262D02*
Y398462D01*
G01X144881Y406262D02*
X157481D01*
G01X144881Y398462D02*
Y406262D01*
G01X158581Y397362D02*
X143781D01*
G01X158581Y407362D02*
Y397362D01*
G01X143781Y407362D02*
X158581D01*
G01X143781Y397362D02*
Y407362D01*
G01X167717Y437795D02*
G03X151181I-8268J0D01*
G01D02*
G03X167717I8268J0D01*
G01D02*
G03X151181I-8268J0D01*
G01D02*
G03X167717I8268J0D01*
G01D02*
G03X151181I-8268J0D01*
G01D02*
G03X167717I8268J0D01*
G01D02*
G03X151181I-8268J0D01*
G01D02*
G03X167717I8268J0D01*
G01X151181D02*
G03X167717I8268J0D01*
G01D02*
G03X151181I-8268J0D01*
G01D02*
G03X167717I8268J0D01*
G01D02*
G03X151181I-8268J0D01*
G01X177166Y422047D02*
Y475984D01*
G01X173229Y418110D02*
G03X177166Y422047I0J3937D01*
G01X211024Y437795D02*
G03X194489I-8267J0D01*
G01D02*
G03X211024I8267J0D01*
G01D02*
G03X194489I-8267J0D01*
G01D02*
G03X211024I8267J0D01*
G01D02*
G03X194489I-8267J0D01*
G01D02*
G03X211024I8267J0D01*
G01D02*
G03X194489I-8267J0D01*
G01D02*
G03X211024I8267J0D01*
G01X194489D02*
G03X211024I8267J0D01*
G01D02*
G03X194489I-8267J0D01*
G01D02*
G03X211024I8267J0D01*
G01D02*
G03X194489I-8267J0D01*
G01X188977Y418110D02*
X358268D01*
G01X185040Y422047D02*
G03X188977Y418110I3937J0D01*
G01X185040Y475984D02*
Y422047D01*
G01X167717Y368110D02*
G03X151181I-8268J0D01*
G01X167717D02*
G03X151181I-8268J0D01*
G01X167717D02*
G03X151181I-8268J0D01*
G01X167717D02*
G03X151181I-8268J0D01*
G01X167717D02*
G03X151181I-8268J0D01*
G01X167717D02*
G03X151181I-8268J0D01*
G01X177166Y406299D02*
G03X173229Y410236I-3937J0D01*
G01X211024Y368110D02*
G03X194489I-8267J0D01*
G01X211024D02*
G03X194489I-8267J0D01*
G01X211024D02*
G03X194489I-8267J0D01*
G01X211024D02*
G03X194489I-8267J0D01*
G01X211024D02*
G03X194489I-8267J0D01*
G01X211024D02*
G03X194489I-8267J0D01*
G01X188977Y410236D02*
G03X185040Y406299I0J-3937D01*
G01X358268Y410236D02*
X188977D01*
G01X185040Y506102D02*
G03X177166I-3937J0D01*
G01Y531299D02*
G03X185040I3937J0D01*
G01X177166Y461614D02*
G03X185040I3937J0D01*
G01X196851Y479921D02*
G03Y487795I0J3937D01*
G01X165355D02*
G03Y479921I0J-3937D01*
G01X140158D02*
G03Y487795I0J3937D01*
G01X151181Y470047D02*
G03Y474047I0J2000D01*
G01D02*
G03Y470047I0J-2000D01*
G01X157481Y468147D02*
X144881D01*
G01X157481Y475947D02*
Y468147D01*
G01X144881Y475947D02*
X157481D01*
G01X144881Y468147D02*
Y475947D01*
G01X158581Y467047D02*
X143781D01*
G01X158581Y477047D02*
Y467047D01*
G01X143781Y477047D02*
X158581D01*
G01X143781Y467047D02*
Y477047D01*
G01X167717Y507480D02*
G03X151181I-8268J0D01*
G01D02*
G03X167717I8268J0D01*
G01D02*
G03X151181I-8268J0D01*
G01D02*
G03X167717I8268J0D01*
G01D02*
G03X151181I-8268J0D01*
G01D02*
G03X167717I8268J0D01*
G01D02*
G03X151181I-8268J0D01*
G01D02*
G03X167717I8268J0D01*
G01X151181D02*
G03X167717I8268J0D01*
G01D02*
G03X151181I-8268J0D01*
G01D02*
G03X167717I8268J0D01*
G01D02*
G03X151181I-8268J0D01*
G01X177166Y491732D02*
Y545669D01*
G01X173229Y487795D02*
G03X177166Y491732I0J3937D01*
G01X211024Y507480D02*
G03X194489I-8267J0D01*
G01D02*
G03X211024I8267J0D01*
G01D02*
G03X194489I-8267J0D01*
G01D02*
G03X211024I8267J0D01*
G01D02*
G03X194489I-8267J0D01*
G01D02*
G03X211024I8267J0D01*
G01D02*
G03X194489I-8267J0D01*
G01D02*
G03X211024I8267J0D01*
G01X194489D02*
G03X211024I8267J0D01*
G01D02*
G03X194489I-8267J0D01*
G01D02*
G03X211024I8267J0D01*
G01D02*
G03X194489I-8267J0D01*
G01X188977Y487795D02*
X358268D01*
G01X185040Y491732D02*
G03X188977Y487795I3937J0D01*
G01X185040Y545669D02*
Y491732D01*
G01X177166Y475984D02*
G03X173229Y479921I-3937J0D01*
G01X188977D02*
G03X185040Y475984I0J-3937D01*
G01X358268Y479921D02*
X188977D01*
G01X185040Y575787D02*
G03X177166I-3937J0D01*
G01Y600984D02*
G03X185040I3937J0D01*
G01X196851Y549606D02*
G03Y557480I0J3937D01*
G01X165355D02*
G03Y549606I0J-3937D01*
G01X140158D02*
G03Y557480I0J3937D01*
G01X151181Y609417D02*
G03Y613417I0J2000D01*
G01D02*
G03Y609417I0J-2000D01*
G01X157481Y607517D02*
X144881D01*
G01X157481Y615317D02*
Y607517D01*
G01X144881D02*
Y615317D01*
G01X158581Y606417D02*
X143781D01*
G01X158581Y616417D02*
Y606417D01*
G01X143781D02*
Y616417D01*
G01X151181Y539732D02*
G03Y543732I0J2000D01*
G01D02*
G03Y539732I0J-2000D01*
G01X157481Y537832D02*
X144881D01*
G01X157481Y545632D02*
Y537832D01*
G01X144881Y545632D02*
X157481D01*
G01X144881Y537832D02*
Y545632D01*
G01X158581Y536732D02*
X143781D01*
G01X158581Y546732D02*
Y536732D01*
G01X143781Y546732D02*
X158581D01*
G01X143781Y536732D02*
Y546732D01*
G01X167717Y577165D02*
G03X151181I-8268J0D01*
G01D02*
G03X167717I8268J0D01*
G01D02*
G03X151181I-8268J0D01*
G01D02*
G03X167717I8268J0D01*
G01D02*
G03X151181I-8268J0D01*
G01D02*
G03X167717I8268J0D01*
G01D02*
G03X151181I-8268J0D01*
G01D02*
G03X167717I8268J0D01*
G01X151181D02*
G03X167717I8268J0D01*
G01D02*
G03X151181I-8268J0D01*
G01D02*
G03X167717I8268J0D01*
G01D02*
G03X151181I-8268J0D01*
G01X177166Y561417D02*
Y615354D01*
G01X173229Y557480D02*
G03X177166Y561417I0J3937D01*
G01X211024Y577165D02*
G03X194489I-8267J0D01*
G01D02*
G03X211024I8267J0D01*
G01D02*
G03X194489I-8267J0D01*
G01D02*
G03X211024I8267J0D01*
G01D02*
G03X194489I-8267J0D01*
G01D02*
G03X211024I8267J0D01*
G01D02*
G03X194489I-8267J0D01*
G01D02*
G03X211024I8267J0D01*
G01X194489D02*
G03X211024I8267J0D01*
G01D02*
G03X194489I-8267J0D01*
G01D02*
G03X211024I8267J0D01*
G01D02*
G03X194489I-8267J0D01*
G01X188977Y557480D02*
X358268D01*
G01X185040Y561417D02*
G03X188977Y557480I3937J0D01*
G01X185040Y615354D02*
Y561417D01*
G01X177166Y545669D02*
G03X173229Y549606I-3937J0D01*
G01X188977D02*
G03X185040Y545669I0J-3937D01*
G01X358268Y549606D02*
X188977D01*
G01X177166Y685285D02*
Y716324D01*
G01X185040Y685285D02*
Y719159D01*
G01Y645472D02*
G03X177166I-3937J0D01*
G01Y670669D02*
G03X185040I3937J0D01*
G01X196851Y619291D02*
G03Y627165I0J3937D01*
G01X165355D02*
G03Y619291I0J-3937D01*
G01X140158D02*
G03Y627165I0J3937D01*
G01X151181Y679102D02*
G03Y683102I0J2000D01*
G01D02*
G03Y679102I0J-2000D01*
G01X157481Y677202D02*
X144881D01*
G01X157481Y685002D02*
Y677202D01*
G01X144881Y685002D02*
X157481D01*
G01X144881Y677202D02*
Y685002D01*
G01X158581Y676102D02*
X143781D01*
G01X158581Y686102D02*
Y676102D01*
G01X143781Y686102D02*
X158581D01*
G01X143781Y676102D02*
Y686102D01*
G01X144881Y615317D02*
X157481D01*
G01X143781Y616417D02*
X158581D01*
G01X167717Y646850D02*
G03X151181I-8268J0D01*
G01D02*
G03X167717I8268J0D01*
G01D02*
G03X151181I-8268J0D01*
G01D02*
G03X167717I8268J0D01*
G01D02*
G03X151181I-8268J0D01*
G01D02*
G03X167717I8268J0D01*
G01D02*
G03X151181I-8268J0D01*
G01D02*
G03X167717I8268J0D01*
G01X151181D02*
G03X167717I8268J0D01*
G01D02*
G03X151181I-8268J0D01*
G01D02*
G03X167717I8268J0D01*
G01D02*
G03X151181I-8268J0D01*
G01X177166Y631102D02*
Y685039D01*
G01X173229Y627165D02*
G03X177166Y631102I0J3937D01*
G01Y685039D02*
G03X173229Y688976I-3937J0D01*
G01X211024Y646850D02*
G03X194489I-8267J0D01*
G01D02*
G03X211024I8267J0D01*
G01D02*
G03X194489I-8267J0D01*
G01D02*
G03X211024I8267J0D01*
G01D02*
G03X194489I-8267J0D01*
G01D02*
G03X211024I8267J0D01*
G01D02*
G03X194489I-8267J0D01*
G01D02*
G03X211024I8267J0D01*
G01X194489D02*
G03X211024I8267J0D01*
G01D02*
G03X194489I-8267J0D01*
G01D02*
G03X211024I8267J0D01*
G01D02*
G03X194489I-8267J0D01*
G01X188977Y627165D02*
X358268D01*
G01X185040Y631102D02*
G03X188977Y627165I3937J0D01*
G01X185040Y685039D02*
Y631102D01*
G01X188977Y688976D02*
G03X185040Y685039I0J-3937D01*
G01X358268Y688976D02*
X188977D01*
G01X177166Y615354D02*
G03X173229Y619291I-3937J0D01*
G01X188977D02*
G03X185040Y615354I0J-3937D01*
G01X358268Y619291D02*
X188977D01*
G01X175580Y717742D02*
Y719159D01*
G01X177166Y716324D02*
X175580Y717742D01*
G01X124807Y978747D02*
Y961424D01*
G01X222048Y-7874D02*
X325197D01*
G01X222048Y0D02*
G03Y-7874I0J-3937D01*
G01X280112Y-18286D02*
Y-21085D01*
G01X248617Y-18286D02*
Y-21085D01*
G01X217122Y-18286D02*
Y-21085D01*
G01X222048Y69685D02*
G03Y61811I0J-3937D01*
G01Y139370D02*
G03Y131496I0J-3937D01*
G01Y278740D02*
G03Y270866I0J-3937D01*
G01Y209055D02*
G03Y201181I0J-3937D01*
G01Y348425D02*
G03Y340551I0J-3937D01*
G01Y418110D02*
G03Y410236I0J-3937D01*
G01Y487795D02*
G03Y479921I0J-3937D01*
G01Y557480D02*
G03Y549606I0J-3937D01*
G01Y627165D02*
G03Y619291I0J-3937D01*
G01X298037Y-381883D02*
Y-399206D01*
G01X370079Y18307D02*
G03X362205I-3937J0D01*
G01X350394Y-7874D02*
X381890D01*
G01X350394Y0D02*
G03Y-7874I0J-3937D01*
G01X325197D02*
G03Y0I0J3937D01*
G01X343102Y-18286D02*
Y-21085D01*
G01X311607Y-18286D02*
Y-21085D01*
G01X352756Y19685D02*
G03X336221I-8267J0D01*
G01D02*
G03X352756I8268J0D01*
G01D02*
G03X336221I-8267J0D01*
G01D02*
G03X352756I8268J0D01*
G01D02*
G03X336221I-8267J0D01*
G01D02*
G03X352756I8268J0D01*
G01D02*
G03X336221I-8267J0D01*
G01D02*
G03X352756I8268J0D01*
G01X336221D02*
G03X352756I8268J0D01*
G01D02*
G03X336221I-8267J0D01*
G01D02*
G03X352756I8268J0D01*
G01D02*
G03X336221I-8267J0D01*
G01X362205Y3937D02*
Y57874D01*
G01X358268Y0D02*
G03X362205Y3937I0J3937D01*
G01X370079Y87992D02*
G03X362205I-3937J0D01*
G01Y113189D02*
G03X370079I3937J0D01*
G01X362205Y43504D02*
G03X370079I3937J0D01*
G01X350394Y69685D02*
G03Y61811I0J-3937D01*
G01X325197D02*
G03Y69685I0J3937D01*
G01X336221Y51937D02*
G03Y55937I0J2000D01*
G01D02*
G03Y51937I0J-2000D01*
G01X342521Y50037D02*
X329921D01*
G01X342521Y57837D02*
Y50037D01*
G01X329921Y57837D02*
X342521D01*
G01X329921Y50037D02*
Y57837D01*
G01X343621Y48937D02*
X328821D01*
G01X343621Y58937D02*
Y48937D01*
G01X328821Y58937D02*
X343621D01*
G01X328821Y48937D02*
Y58937D01*
G01X352756Y89370D02*
G03X336221I-8267J0D01*
G01D02*
G03X352756I8268J0D01*
G01D02*
G03X336221I-8267J0D01*
G01D02*
G03X352756I8268J0D01*
G01D02*
G03X336221I-8267J0D01*
G01D02*
G03X352756I8268J0D01*
G01D02*
G03X336221I-8267J0D01*
G01D02*
G03X352756I8268J0D01*
G01X336221D02*
G03X352756I8268J0D01*
G01D02*
G03X336221I-8267J0D01*
G01D02*
G03X352756I8268J0D01*
G01D02*
G03X336221I-8267J0D01*
G01X362205Y73622D02*
Y127559D01*
G01X358268Y69685D02*
G03X362205Y73622I0J3937D01*
G01Y57874D02*
G03X358268Y61811I-3937J0D01*
G01X370079Y157677D02*
G03X362205I-3937J0D01*
G01Y182874D02*
G03X370079I3937J0D01*
G01X350394Y139370D02*
G03Y131496I0J-3937D01*
G01X325197D02*
G03Y139370I0J3937D01*
G01X336221Y191307D02*
G03Y195307I0J2000D01*
G01D02*
G03Y191307I0J-2000D01*
G01X342521Y189407D02*
X329921D01*
G01X342521Y197207D02*
Y189407D01*
G01X329921D02*
Y197207D01*
G01X343621Y188307D02*
X328821D01*
G01X343621Y198307D02*
Y188307D01*
G01X328821D02*
Y198307D01*
G01X336221Y121622D02*
G03Y125622I0J2000D01*
G01D02*
G03Y121622I0J-2000D01*
G01X342521Y119722D02*
X329921D01*
G01X342521Y127522D02*
Y119722D01*
G01X329921Y127522D02*
X342521D01*
G01X329921Y119722D02*
Y127522D01*
G01X343621Y118622D02*
X328821D01*
G01X343621Y128622D02*
Y118622D01*
G01X328821Y128622D02*
X343621D01*
G01X328821Y118622D02*
Y128622D01*
G01X352756Y159055D02*
G03X336221I-8267J0D01*
G01D02*
G03X352756I8268J0D01*
G01D02*
G03X336221I-8267J0D01*
G01D02*
G03X352756I8268J0D01*
G01D02*
G03X336221I-8267J0D01*
G01D02*
G03X352756I8268J0D01*
G01D02*
G03X336221I-8267J0D01*
G01D02*
G03X352756I8268J0D01*
G01X336221D02*
G03X352756I8268J0D01*
G01D02*
G03X336221I-8267J0D01*
G01D02*
G03X352756I8268J0D01*
G01D02*
G03X336221I-8267J0D01*
G01X362205Y143307D02*
Y197244D01*
G01X358268Y139370D02*
G03X362205Y143307I0J3937D01*
G01Y127559D02*
G03X358268Y131496I-3937J0D01*
G01X370079Y227362D02*
G03X362205I-3937J0D01*
G01Y252559D02*
G03X370079I3937J0D01*
G01X350394Y278740D02*
G03Y270866I0J-3937D01*
G01X325197D02*
G03Y278740I0J3937D01*
G01X350394Y209055D02*
G03Y201181I0J-3937D01*
G01X325197D02*
G03Y209055I0J3937D01*
G01X336221Y260992D02*
G03Y264992I0J2000D01*
G01D02*
G03Y260992I0J-2000D01*
G01X342521Y259092D02*
X329921D01*
G01X342521Y266892D02*
Y259092D01*
G01X329921Y266892D02*
X342521D01*
G01X329921Y259092D02*
Y266892D01*
G01X343621Y257992D02*
X328821D01*
G01X343621Y267992D02*
Y257992D01*
G01X328821Y267992D02*
X343621D01*
G01X328821Y257992D02*
Y267992D01*
G01X329921Y197207D02*
X342521D01*
G01X328821Y198307D02*
X343621D01*
G01X358268Y278740D02*
G03X362205Y282677I0J3937D01*
G01X352756Y228740D02*
G03X336221I-8267J0D01*
G01D02*
G03X352756I8268J0D01*
G01D02*
G03X336221I-8267J0D01*
G01D02*
G03X352756I8268J0D01*
G01D02*
G03X336221I-8267J0D01*
G01D02*
G03X352756I8268J0D01*
G01D02*
G03X336221I-8267J0D01*
G01D02*
G03X352756I8268J0D01*
G01X336221D02*
G03X352756I8268J0D01*
G01D02*
G03X336221I-8267J0D01*
G01D02*
G03X352756I8268J0D01*
G01D02*
G03X336221I-8267J0D01*
G01X362205Y212992D02*
Y266929D01*
G01X358268Y209055D02*
G03X362205Y212992I0J3937D01*
G01Y266929D02*
G03X358268Y270866I-3937J0D01*
G01X362205Y197244D02*
G03X358268Y201181I-3937J0D01*
G01X370079Y297047D02*
G03X362205I-3937J0D01*
G01Y322244D02*
G03X370079I3937J0D01*
G01X350394Y348425D02*
G03Y340551I0J-3937D01*
G01X325197D02*
G03Y348425I0J3937D01*
G01X336221Y330677D02*
G03Y334677I0J2000D01*
G01D02*
G03Y330677I0J-2000D01*
G01X342521Y328777D02*
X329921D01*
G01X342521Y336577D02*
Y328777D01*
G01X329921Y336577D02*
X342521D01*
G01X329921Y328777D02*
Y336577D01*
G01X343621Y327677D02*
X328821D01*
G01X343621Y337677D02*
Y327677D01*
G01X328821Y337677D02*
X343621D01*
G01X328821Y327677D02*
Y337677D01*
G01X336221Y368110D02*
G03X352756I8268J0D01*
G01X336221D02*
G03X352756I8268J0D01*
G01X336221D02*
G03X352756I8268J0D01*
G01X336221D02*
G03X352756I8268J0D01*
G01X336221D02*
G03X352756I8268J0D01*
G01X336221D02*
G03X352756I8268J0D01*
G01X362205Y352362D02*
Y406299D01*
G01X358268Y348425D02*
G03X362205Y352362I0J3937D01*
G01X352756Y298425D02*
G03X336221I-8267J0D01*
G01D02*
G03X352756I8268J0D01*
G01D02*
G03X336221I-8267J0D01*
G01D02*
G03X352756I8268J0D01*
G01D02*
G03X336221I-8267J0D01*
G01D02*
G03X352756I8268J0D01*
G01D02*
G03X336221I-8267J0D01*
G01D02*
G03X352756I8268J0D01*
G01X336221D02*
G03X352756I8268J0D01*
G01D02*
G03X336221I-8267J0D01*
G01D02*
G03X352756I8268J0D01*
G01D02*
G03X336221I-8267J0D01*
G01X362205Y282677D02*
Y336614D01*
G01D02*
G03X358268Y340551I-3937J0D01*
G01X370079Y436417D02*
G03X362205I-3937J0D01*
G01X370079Y366732D02*
G03X362205I-3937J0D01*
G01Y391929D02*
G03X370079I3937J0D01*
G01X350394Y418110D02*
G03Y410236I0J-3937D01*
G01X325197D02*
G03Y418110I0J3937D01*
G01X336221Y400362D02*
G03Y404362I0J2000D01*
G01D02*
G03Y400362I0J-2000D01*
G01X342521Y398462D02*
X329921D01*
G01X342521Y406262D02*
Y398462D01*
G01X329921Y406262D02*
X342521D01*
G01X329921Y398462D02*
Y406262D01*
G01X343621Y397362D02*
X328821D01*
G01X343621Y407362D02*
Y397362D01*
G01X328821Y407362D02*
X343621D01*
G01X328821Y397362D02*
Y407362D01*
G01X352756Y437795D02*
G03X336221I-8267J0D01*
G01D02*
G03X352756I8268J0D01*
G01D02*
G03X336221I-8267J0D01*
G01D02*
G03X352756I8268J0D01*
G01D02*
G03X336221I-8267J0D01*
G01D02*
G03X352756I8268J0D01*
G01D02*
G03X336221I-8267J0D01*
G01D02*
G03X352756I8268J0D01*
G01X336221D02*
G03X352756I8268J0D01*
G01D02*
G03X336221I-8267J0D01*
G01D02*
G03X352756I8268J0D01*
G01D02*
G03X336221I-8267J0D01*
G01X362205Y422047D02*
Y475984D01*
G01X358268Y418110D02*
G03X362205Y422047I0J3937D01*
G01X352756Y368110D02*
G03X336221I-8267J0D01*
G01X352756D02*
G03X336221I-8267J0D01*
G01X352756D02*
G03X336221I-8267J0D01*
G01X352756D02*
G03X336221I-8267J0D01*
G01X352756D02*
G03X336221I-8267J0D01*
G01X352756D02*
G03X336221I-8267J0D01*
G01X362205Y406299D02*
G03X358268Y410236I-3937J0D01*
G01X370079Y506102D02*
G03X362205I-3937J0D01*
G01Y531299D02*
G03X370079I3937J0D01*
G01X362205Y461614D02*
G03X370079I3937J0D01*
G01X350394Y487795D02*
G03Y479921I0J-3937D01*
G01X325197D02*
G03Y487795I0J3937D01*
G01X336221Y470047D02*
G03Y474047I0J2000D01*
G01D02*
G03Y470047I0J-2000D01*
G01X342521Y468147D02*
X329921D01*
G01X342521Y475947D02*
Y468147D01*
G01X329921Y475947D02*
X342521D01*
G01X329921Y468147D02*
Y475947D01*
G01X343621Y467047D02*
X328821D01*
G01X343621Y477047D02*
Y467047D01*
G01X328821Y477047D02*
X343621D01*
G01X328821Y467047D02*
Y477047D01*
G01X352756Y507480D02*
G03X336221I-8267J0D01*
G01D02*
G03X352756I8268J0D01*
G01D02*
G03X336221I-8267J0D01*
G01D02*
G03X352756I8268J0D01*
G01D02*
G03X336221I-8267J0D01*
G01D02*
G03X352756I8268J0D01*
G01D02*
G03X336221I-8267J0D01*
G01D02*
G03X352756I8268J0D01*
G01X336221D02*
G03X352756I8268J0D01*
G01D02*
G03X336221I-8267J0D01*
G01D02*
G03X352756I8268J0D01*
G01D02*
G03X336221I-8267J0D01*
G01X362205Y491732D02*
Y545669D01*
G01X358268Y487795D02*
G03X362205Y491732I0J3937D01*
G01Y475984D02*
G03X358268Y479921I-3937J0D01*
G01X370079Y575787D02*
G03X362205I-3937J0D01*
G01Y600984D02*
G03X370079I3937J0D01*
G01X350394Y557480D02*
G03Y549606I0J-3937D01*
G01X325197D02*
G03Y557480I0J3937D01*
G01X336221Y609417D02*
G03Y613417I0J2000D01*
G01D02*
G03Y609417I0J-2000D01*
G01X342521Y607517D02*
X329921D01*
G01X342521Y615317D02*
Y607517D01*
G01X329921D02*
Y615317D01*
G01X343621Y606417D02*
X328821D01*
G01X343621Y616417D02*
Y606417D01*
G01X328821D02*
Y616417D01*
G01X336221Y539732D02*
G03Y543732I0J2000D01*
G01D02*
G03Y539732I0J-2000D01*
G01X342521Y537832D02*
X329921D01*
G01X342521Y545632D02*
Y537832D01*
G01X329921Y545632D02*
X342521D01*
G01X329921Y537832D02*
Y545632D01*
G01X343621Y536732D02*
X328821D01*
G01X343621Y546732D02*
Y536732D01*
G01X328821Y546732D02*
X343621D01*
G01X328821Y536732D02*
Y546732D01*
G01X352756Y577165D02*
G03X336221I-8267J0D01*
G01D02*
G03X352756I8268J0D01*
G01D02*
G03X336221I-8267J0D01*
G01D02*
G03X352756I8268J0D01*
G01D02*
G03X336221I-8267J0D01*
G01D02*
G03X352756I8268J0D01*
G01D02*
G03X336221I-8267J0D01*
G01D02*
G03X352756I8268J0D01*
G01X336221D02*
G03X352756I8268J0D01*
G01D02*
G03X336221I-8267J0D01*
G01D02*
G03X352756I8268J0D01*
G01D02*
G03X336221I-8267J0D01*
G01X362205Y561417D02*
Y615354D01*
G01X358268Y557480D02*
G03X362205Y561417I0J3937D01*
G01Y545669D02*
G03X358268Y549606I-3937J0D01*
G01X362205Y685285D02*
Y716324D01*
G01X370079Y645472D02*
G03X362205I-3937J0D01*
G01Y670669D02*
G03X370079I3937J0D01*
G01X350394Y627165D02*
G03Y619291I0J-3937D01*
G01X325197D02*
G03Y627165I0J3937D01*
G01X336221Y679102D02*
G03Y683102I0J2000D01*
G01D02*
G03Y679102I0J-2000D01*
G01X342521Y677202D02*
X329921D01*
G01X342521Y685002D02*
Y677202D01*
G01X329921Y685002D02*
X342521D01*
G01X329921Y677202D02*
Y685002D01*
G01X343621Y676102D02*
X328821D01*
G01X343621Y686102D02*
Y676102D01*
G01X328821Y686102D02*
X343621D01*
G01X328821Y676102D02*
Y686102D01*
G01X329921Y615317D02*
X342521D01*
G01X328821Y616417D02*
X343621D01*
G01X352756Y646850D02*
G03X336221I-8267J0D01*
G01D02*
G03X352756I8268J0D01*
G01D02*
G03X336221I-8267J0D01*
G01D02*
G03X352756I8268J0D01*
G01D02*
G03X336221I-8267J0D01*
G01D02*
G03X352756I8268J0D01*
G01D02*
G03X336221I-8267J0D01*
G01D02*
G03X352756I8268J0D01*
G01X336221D02*
G03X352756I8268J0D01*
G01D02*
G03X336221I-8267J0D01*
G01D02*
G03X352756I8268J0D01*
G01D02*
G03X336221I-8267J0D01*
G01X362205Y631102D02*
Y685039D01*
G01X358268Y627165D02*
G03X362205Y631102I0J3937D01*
G01Y685039D02*
G03X358268Y688976I-3937J0D01*
G01X362205Y615354D02*
G03X358268Y619291I-3937J0D01*
G01X359825Y717742D02*
Y719159D01*
G01X362205Y716324D02*
X359825Y717742D01*
G01X298037Y978747D02*
Y961424D01*
G01X407087Y-7874D02*
X510237D01*
G01X407087Y0D02*
G03Y-7874I0J-3937D01*
G01X381890D02*
G03Y0I0J3937D01*
G01X374598Y-18286D02*
Y-21085D01*
G01X396063Y19685D02*
G03X379528I-8268J0D01*
G01D02*
G03X396063I8267J0D01*
G01D02*
G03X379528I-8268J0D01*
G01D02*
G03X396063I8267J0D01*
G01D02*
G03X379528I-8268J0D01*
G01D02*
G03X396063I8267J0D01*
G01D02*
G03X379528I-8268J0D01*
G01D02*
G03X396063I8267J0D01*
G01X379528D02*
G03X396063I8267J0D01*
G01D02*
G03X379528I-8268J0D01*
G01D02*
G03X396063I8267J0D01*
G01D02*
G03X379528I-8268J0D01*
G01X374016Y0D02*
X543307D01*
G01X370079Y3937D02*
G03X374016Y0I3937J0D01*
G01X370079Y57874D02*
Y3937D01*
G01X407087Y69685D02*
G03Y61811I0J-3937D01*
G01X381890D02*
G03Y69685I0J3937D01*
G01X396063Y89370D02*
G03X379528I-8268J0D01*
G01D02*
G03X396063I8267J0D01*
G01D02*
G03X379528I-8268J0D01*
G01D02*
G03X396063I8267J0D01*
G01D02*
G03X379528I-8268J0D01*
G01D02*
G03X396063I8267J0D01*
G01D02*
G03X379528I-8268J0D01*
G01D02*
G03X396063I8267J0D01*
G01X379528D02*
G03X396063I8267J0D01*
G01D02*
G03X379528I-8268J0D01*
G01D02*
G03X396063I8267J0D01*
G01D02*
G03X379528I-8268J0D01*
G01X374016Y69685D02*
X543307D01*
G01X370079Y73622D02*
G03X374016Y69685I3937J0D01*
G01X370079Y127559D02*
Y73622D01*
G01X374016Y61811D02*
G03X370079Y57874I0J-3937D01*
G01X543307Y61811D02*
X374016D01*
G01X407087Y139370D02*
G03Y131496I0J-3937D01*
G01X381890D02*
G03Y139370I0J3937D01*
G01X396063Y159055D02*
G03X379528I-8268J0D01*
G01D02*
G03X396063I8267J0D01*
G01D02*
G03X379528I-8268J0D01*
G01D02*
G03X396063I8267J0D01*
G01D02*
G03X379528I-8268J0D01*
G01D02*
G03X396063I8267J0D01*
G01D02*
G03X379528I-8268J0D01*
G01D02*
G03X396063I8267J0D01*
G01X379528D02*
G03X396063I8267J0D01*
G01D02*
G03X379528I-8268J0D01*
G01D02*
G03X396063I8267J0D01*
G01D02*
G03X379528I-8268J0D01*
G01X374016Y139370D02*
X543307D01*
G01X370079Y143307D02*
G03X374016Y139370I3937J0D01*
G01X370079Y197244D02*
Y143307D01*
G01X374016Y131496D02*
G03X370079Y127559I0J-3937D01*
G01X543307Y131496D02*
X374016D01*
G01X407087Y278740D02*
G03Y270866I0J-3937D01*
G01X381890D02*
G03Y278740I0J3937D01*
G01X407087Y209055D02*
G03Y201181I0J-3937D01*
G01X381890D02*
G03Y209055I0J3937D01*
G01X374016Y278740D02*
X543307D01*
G01X370079Y282677D02*
G03X374016Y278740I3937J0D01*
G01X396063Y228740D02*
G03X379528I-8268J0D01*
G01D02*
G03X396063I8267J0D01*
G01D02*
G03X379528I-8268J0D01*
G01D02*
G03X396063I8267J0D01*
G01D02*
G03X379528I-8268J0D01*
G01D02*
G03X396063I8267J0D01*
G01D02*
G03X379528I-8268J0D01*
G01D02*
G03X396063I8267J0D01*
G01X379528D02*
G03X396063I8267J0D01*
G01D02*
G03X379528I-8268J0D01*
G01D02*
G03X396063I8267J0D01*
G01D02*
G03X379528I-8268J0D01*
G01X374016Y209055D02*
X543307D01*
G01X370079Y212992D02*
G03X374016Y209055I3937J0D01*
G01X370079Y266929D02*
Y212992D01*
G01X374016Y270866D02*
G03X370079Y266929I0J-3937D01*
G01X543307Y270866D02*
X374016D01*
G01Y201181D02*
G03X370079Y197244I0J-3937D01*
G01X543307Y201181D02*
X374016D01*
G01X407087Y348425D02*
G03Y340551I0J-3937D01*
G01X381890D02*
G03Y348425I0J3937D01*
G01X379528Y368110D02*
G03X396063I8267J0D01*
G01X379528D02*
G03X396063I8267J0D01*
G01X379528D02*
G03X396063I8267J0D01*
G01X379528D02*
G03X396063I8267J0D01*
G01X379528D02*
G03X396063I8267J0D01*
G01X379528D02*
G03X396063I8267J0D01*
G01X374016Y348425D02*
X543307D01*
G01X370079Y352362D02*
G03X374016Y348425I3937J0D01*
G01X370079Y406299D02*
Y352362D01*
G01X396063Y298425D02*
G03X379528I-8268J0D01*
G01D02*
G03X396063I8267J0D01*
G01D02*
G03X379528I-8268J0D01*
G01D02*
G03X396063I8267J0D01*
G01D02*
G03X379528I-8268J0D01*
G01D02*
G03X396063I8267J0D01*
G01D02*
G03X379528I-8268J0D01*
G01D02*
G03X396063I8267J0D01*
G01X379528D02*
G03X396063I8267J0D01*
G01D02*
G03X379528I-8268J0D01*
G01D02*
G03X396063I8267J0D01*
G01D02*
G03X379528I-8268J0D01*
G01X370079Y336614D02*
Y282677D01*
G01X374016Y340551D02*
G03X370079Y336614I0J-3937D01*
G01X543307Y340551D02*
X374016D01*
G01X407087Y418110D02*
G03Y410236I0J-3937D01*
G01X381890D02*
G03Y418110I0J3937D01*
G01X396063Y437795D02*
G03X379528I-8268J0D01*
G01D02*
G03X396063I8267J0D01*
G01D02*
G03X379528I-8268J0D01*
G01D02*
G03X396063I8267J0D01*
G01D02*
G03X379528I-8268J0D01*
G01D02*
G03X396063I8267J0D01*
G01D02*
G03X379528I-8268J0D01*
G01D02*
G03X396063I8267J0D01*
G01X379528D02*
G03X396063I8267J0D01*
G01D02*
G03X379528I-8268J0D01*
G01D02*
G03X396063I8267J0D01*
G01D02*
G03X379528I-8268J0D01*
G01X374016Y418110D02*
X543307D01*
G01X370079Y422047D02*
G03X374016Y418110I3937J0D01*
G01X370079Y475984D02*
Y422047D01*
G01X396063Y368110D02*
G03X379528I-8268J0D01*
G01X396063D02*
G03X379528I-8268J0D01*
G01X396063D02*
G03X379528I-8268J0D01*
G01X396063D02*
G03X379528I-8268J0D01*
G01X396063D02*
G03X379528I-8268J0D01*
G01X396063D02*
G03X379528I-8268J0D01*
G01X374016Y410236D02*
G03X370079Y406299I0J-3937D01*
G01X543307Y410236D02*
X374016D01*
G01X407087Y487795D02*
G03Y479921I0J-3937D01*
G01X381890D02*
G03Y487795I0J3937D01*
G01X396063Y507480D02*
G03X379528I-8268J0D01*
G01D02*
G03X396063I8267J0D01*
G01D02*
G03X379528I-8268J0D01*
G01D02*
G03X396063I8267J0D01*
G01D02*
G03X379528I-8268J0D01*
G01D02*
G03X396063I8267J0D01*
G01D02*
G03X379528I-8268J0D01*
G01D02*
G03X396063I8267J0D01*
G01X379528D02*
G03X396063I8267J0D01*
G01D02*
G03X379528I-8268J0D01*
G01D02*
G03X396063I8267J0D01*
G01D02*
G03X379528I-8268J0D01*
G01X374016Y487795D02*
X543307D01*
G01X370079Y491732D02*
G03X374016Y487795I3937J0D01*
G01X370079Y545669D02*
Y491732D01*
G01X374016Y479921D02*
G03X370079Y475984I0J-3937D01*
G01X543307Y479921D02*
X374016D01*
G01X407087Y557480D02*
G03Y549606I0J-3937D01*
G01X381890D02*
G03Y557480I0J3937D01*
G01X396063Y577165D02*
G03X379528I-8268J0D01*
G01D02*
G03X396063I8267J0D01*
G01D02*
G03X379528I-8268J0D01*
G01D02*
G03X396063I8267J0D01*
G01D02*
G03X379528I-8268J0D01*
G01D02*
G03X396063I8267J0D01*
G01D02*
G03X379528I-8268J0D01*
G01D02*
G03X396063I8267J0D01*
G01X379528D02*
G03X396063I8267J0D01*
G01D02*
G03X379528I-8268J0D01*
G01D02*
G03X396063I8267J0D01*
G01D02*
G03X379528I-8268J0D01*
G01X374016Y557480D02*
X543307D01*
G01X370079Y561417D02*
G03X374016Y557480I3937J0D01*
G01X370079Y615354D02*
Y561417D01*
G01X374016Y549606D02*
G03X370079Y545669I0J-3937D01*
G01X543307Y549606D02*
X374016D01*
G01X370079Y685285D02*
Y719159D01*
G01X407087Y627165D02*
G03Y619291I0J-3937D01*
G01X381890D02*
G03Y627165I0J3937D01*
G01X396063Y646850D02*
G03X379528I-8268J0D01*
G01D02*
G03X396063I8267J0D01*
G01D02*
G03X379528I-8268J0D01*
G01D02*
G03X396063I8267J0D01*
G01D02*
G03X379528I-8268J0D01*
G01D02*
G03X396063I8267J0D01*
G01D02*
G03X379528I-8268J0D01*
G01D02*
G03X396063I8267J0D01*
G01X379528D02*
G03X396063I8267J0D01*
G01D02*
G03X379528I-8268J0D01*
G01D02*
G03X396063I8267J0D01*
G01D02*
G03X379528I-8268J0D01*
G01X374016Y627165D02*
X543307D01*
G01X370079Y631102D02*
G03X374016Y627165I3937J0D01*
G01X370079Y685039D02*
Y631102D01*
G01X374016Y688976D02*
G03X370079Y685039I0J-3937D01*
G01X543307Y688976D02*
X374016D01*
G01Y619291D02*
G03X370079Y615354I0J-3937D01*
G01X543307Y619291D02*
X374016D01*
G01X471265Y-381883D02*
Y-399206D01*
G01X523227Y-9492D02*
G03I-4000J0D01*
G01X521227D02*
G03I-2000J0D01*
G01X510237Y-7874D02*
G03Y0I0J3937D01*
G01X537796Y19685D02*
G03X521260I-8268J0D01*
G01D02*
G03X537796I8268J0D01*
G01D02*
G03X521260I-8268J0D01*
G01D02*
G03X537796I8268J0D01*
G01D02*
G03X521260I-8268J0D01*
G01D02*
G03X537796I8268J0D01*
G01D02*
G03X521260I-8268J0D01*
G01D02*
G03X537796I8268J0D01*
G01X521260D02*
G03X537796I8268J0D01*
G01D02*
G03X521260I-8268J0D01*
G01D02*
G03X537796I8268J0D01*
G01D02*
G03X521260I-8268J0D01*
G01X510237Y61811D02*
G03Y69685I0J3937D01*
G01X521260Y51937D02*
G03Y55937I0J2000D01*
G01D02*
G03Y51937I0J-2000D01*
G01X527560Y50037D02*
X514960D01*
G01X527560Y57837D02*
Y50037D01*
G01X514960Y57837D02*
X527560D01*
G01X514960Y50037D02*
Y57837D01*
G01X528660Y48937D02*
X513860D01*
G01X528660Y58937D02*
Y48937D01*
G01X513860Y58937D02*
X528660D01*
G01X513860Y48937D02*
Y58937D01*
G01X537796Y89370D02*
G03X521260I-8268J0D01*
G01D02*
G03X537796I8268J0D01*
G01D02*
G03X521260I-8268J0D01*
G01D02*
G03X537796I8268J0D01*
G01D02*
G03X521260I-8268J0D01*
G01D02*
G03X537796I8268J0D01*
G01D02*
G03X521260I-8268J0D01*
G01D02*
G03X537796I8268J0D01*
G01X521260D02*
G03X537796I8268J0D01*
G01D02*
G03X521260I-8268J0D01*
G01D02*
G03X537796I8268J0D01*
G01D02*
G03X521260I-8268J0D01*
G01X528660Y48937D02*
X543875Y33722D01*
G01X535730Y45402D02*
X528660Y48937D01*
G01D02*
X532195Y41867D01*
G01X510237Y131496D02*
G03Y139370I0J3937D01*
G01X521260Y191307D02*
G03Y195307I0J2000D01*
G01D02*
G03Y191307I0J-2000D01*
G01X527560Y189407D02*
X514960D01*
G01X527560Y197207D02*
Y189407D01*
G01X514960D02*
Y197207D01*
G01X528660Y188307D02*
X513860D01*
G01X528660Y198307D02*
Y188307D01*
G01X513860D02*
Y198307D01*
G01X521260Y121622D02*
G03Y125622I0J2000D01*
G01D02*
G03Y121622I0J-2000D01*
G01X527560Y119722D02*
X514960D01*
G01X527560Y127522D02*
Y119722D01*
G01X514960Y127522D02*
X527560D01*
G01X514960Y119722D02*
Y127522D01*
G01X528660Y118622D02*
X513860D01*
G01X528660Y128622D02*
Y118622D01*
G01X513860Y128622D02*
X528660D01*
G01X513860Y118622D02*
Y128622D01*
G01X537796Y159055D02*
G03X521260I-8268J0D01*
G01D02*
G03X537796I8268J0D01*
G01D02*
G03X521260I-8268J0D01*
G01D02*
G03X537796I8268J0D01*
G01D02*
G03X521260I-8268J0D01*
G01D02*
G03X537796I8268J0D01*
G01D02*
G03X521260I-8268J0D01*
G01D02*
G03X537796I8268J0D01*
G01X521260D02*
G03X537796I8268J0D01*
G01D02*
G03X521260I-8268J0D01*
G01D02*
G03X537796I8268J0D01*
G01D02*
G03X521260I-8268J0D01*
G01X510237Y270866D02*
G03Y278740I0J3937D01*
G01Y201181D02*
G03Y209055I0J3937D01*
G01X521260Y260992D02*
G03Y264992I0J2000D01*
G01D02*
G03Y260992I0J-2000D01*
G01X527560Y259092D02*
X514960D01*
G01X527560Y266892D02*
Y259092D01*
G01X514960Y266892D02*
X527560D01*
G01X514960Y259092D02*
Y266892D01*
G01X528660Y257992D02*
X513860D01*
G01X528660Y267992D02*
Y257992D01*
G01X513860Y267992D02*
X528660D01*
G01X513860Y257992D02*
Y267992D01*
G01X514960Y197207D02*
X527560D01*
G01X513860Y198307D02*
X528660D01*
G01X537796Y228740D02*
G03X521260I-8268J0D01*
G01D02*
G03X537796I8268J0D01*
G01D02*
G03X521260I-8268J0D01*
G01D02*
G03X537796I8268J0D01*
G01D02*
G03X521260I-8268J0D01*
G01D02*
G03X537796I8268J0D01*
G01D02*
G03X521260I-8268J0D01*
G01D02*
G03X537796I8268J0D01*
G01X521260D02*
G03X537796I8268J0D01*
G01D02*
G03X521260I-8268J0D01*
G01D02*
G03X537796I8268J0D01*
G01D02*
G03X521260I-8268J0D01*
G01X510237Y340551D02*
G03Y348425I0J3937D01*
G01X521260Y330677D02*
G03Y334677I0J2000D01*
G01D02*
G03Y330677I0J-2000D01*
G01X527560Y328777D02*
X514960D01*
G01X527560Y336577D02*
Y328777D01*
G01X514960Y336577D02*
X527560D01*
G01X514960Y328777D02*
Y336577D01*
G01X528660Y327677D02*
X513860D01*
G01X528660Y337677D02*
Y327677D01*
G01X513860Y337677D02*
X528660D01*
G01X513860Y327677D02*
Y337677D01*
G01X521260Y368110D02*
G03X537796I8268J0D01*
G01X521260D02*
G03X537796I8268J0D01*
G01X521260D02*
G03X537796I8268J0D01*
G01X521260D02*
G03X537796I8268J0D01*
G01X521260D02*
G03X537796I8268J0D01*
G01X521260D02*
G03X537796I8268J0D01*
G01Y298425D02*
G03X521260I-8268J0D01*
G01D02*
G03X537796I8268J0D01*
G01D02*
G03X521260I-8268J0D01*
G01D02*
G03X537796I8268J0D01*
G01D02*
G03X521260I-8268J0D01*
G01D02*
G03X537796I8268J0D01*
G01D02*
G03X521260I-8268J0D01*
G01D02*
G03X537796I8268J0D01*
G01X521260D02*
G03X537796I8268J0D01*
G01D02*
G03X521260I-8268J0D01*
G01D02*
G03X537796I8268J0D01*
G01D02*
G03X521260I-8268J0D01*
G01X510237Y410236D02*
G03Y418110I0J3937D01*
G01X521260Y400362D02*
G03Y404362I0J2000D01*
G01D02*
G03Y400362I0J-2000D01*
G01X527560Y398462D02*
X514960D01*
G01X527560Y406262D02*
Y398462D01*
G01X514960Y406262D02*
X527560D01*
G01X514960Y398462D02*
Y406262D01*
G01X528660Y397362D02*
X513860D01*
G01X528660Y407362D02*
Y397362D01*
G01X513860Y407362D02*
X528660D01*
G01X513860Y397362D02*
Y407362D01*
G01X537796Y437795D02*
G03X521260I-8268J0D01*
G01D02*
G03X537796I8268J0D01*
G01D02*
G03X521260I-8268J0D01*
G01D02*
G03X537796I8268J0D01*
G01D02*
G03X521260I-8268J0D01*
G01D02*
G03X537796I8268J0D01*
G01D02*
G03X521260I-8268J0D01*
G01D02*
G03X537796I8268J0D01*
G01X521260D02*
G03X537796I8268J0D01*
G01D02*
G03X521260I-8268J0D01*
G01D02*
G03X537796I8268J0D01*
G01D02*
G03X521260I-8268J0D01*
G01X537796Y368110D02*
G03X521260I-8268J0D01*
G01X537796D02*
G03X521260I-8268J0D01*
G01X537796D02*
G03X521260I-8268J0D01*
G01X537796D02*
G03X521260I-8268J0D01*
G01X537796D02*
G03X521260I-8268J0D01*
G01X537796D02*
G03X521260I-8268J0D01*
G01X510237Y479921D02*
G03Y487795I0J3937D01*
G01X521260Y470047D02*
G03Y474047I0J2000D01*
G01D02*
G03Y470047I0J-2000D01*
G01X527560Y468147D02*
X514960D01*
G01X527560Y475947D02*
Y468147D01*
G01X514960Y475947D02*
X527560D01*
G01X514960Y468147D02*
Y475947D01*
G01X528660Y467047D02*
X513860D01*
G01X528660Y477047D02*
Y467047D01*
G01X513860Y477047D02*
X528660D01*
G01X513860Y467047D02*
Y477047D01*
G01X537796Y507480D02*
G03X521260I-8268J0D01*
G01D02*
G03X537796I8268J0D01*
G01D02*
G03X521260I-8268J0D01*
G01D02*
G03X537796I8268J0D01*
G01D02*
G03X521260I-8268J0D01*
G01D02*
G03X537796I8268J0D01*
G01D02*
G03X521260I-8268J0D01*
G01D02*
G03X537796I8268J0D01*
G01X521260D02*
G03X537796I8268J0D01*
G01D02*
G03X521260I-8268J0D01*
G01D02*
G03X537796I8268J0D01*
G01D02*
G03X521260I-8268J0D01*
G01X510237Y549606D02*
G03Y557480I0J3937D01*
G01X521260Y609417D02*
G03Y613417I0J2000D01*
G01D02*
G03Y609417I0J-2000D01*
G01X527560Y607517D02*
X514960D01*
G01X527560Y615317D02*
Y607517D01*
G01X514960D02*
Y615317D01*
G01X528660Y606417D02*
X513860D01*
G01X528660Y616417D02*
Y606417D01*
G01X513860D02*
Y616417D01*
G01X521260Y539732D02*
G03Y543732I0J2000D01*
G01D02*
G03Y539732I0J-2000D01*
G01X527560Y537832D02*
X514960D01*
G01X527560Y545632D02*
Y537832D01*
G01X514960Y545632D02*
X527560D01*
G01X514960Y537832D02*
Y545632D01*
G01X528660Y536732D02*
X513860D01*
G01X528660Y546732D02*
Y536732D01*
G01X513860Y546732D02*
X528660D01*
G01X513860Y536732D02*
Y546732D01*
G01X537796Y577165D02*
G03X521260I-8268J0D01*
G01D02*
G03X537796I8268J0D01*
G01D02*
G03X521260I-8268J0D01*
G01D02*
G03X537796I8268J0D01*
G01D02*
G03X521260I-8268J0D01*
G01D02*
G03X537796I8268J0D01*
G01D02*
G03X521260I-8268J0D01*
G01D02*
G03X537796I8268J0D01*
G01X521260D02*
G03X537796I8268J0D01*
G01D02*
G03X521260I-8268J0D01*
G01D02*
G03X537796I8268J0D01*
G01D02*
G03X521260I-8268J0D01*
G01X510237Y619291D02*
G03Y627165I0J3937D01*
G01X521260Y679102D02*
G03Y683102I0J2000D01*
G01D02*
G03Y679102I0J-2000D01*
G01X527560Y677202D02*
X514960D01*
G01X527560Y685002D02*
Y677202D01*
G01X514960Y685002D02*
X527560D01*
G01X514960Y677202D02*
Y685002D01*
G01X528660Y676102D02*
X513860D01*
G01X528660Y686102D02*
Y676102D01*
G01X513860Y686102D02*
X528660D01*
G01X513860Y676102D02*
Y686102D01*
G01X514960Y615317D02*
X527560D01*
G01X513860Y616417D02*
X528660D01*
G01X537796Y646850D02*
G03X521260I-8268J0D01*
G01D02*
G03X537796I8268J0D01*
G01D02*
G03X521260I-8268J0D01*
G01D02*
G03X537796I8268J0D01*
G01D02*
G03X521260I-8268J0D01*
G01D02*
G03X537796I8268J0D01*
G01D02*
G03X521260I-8268J0D01*
G01D02*
G03X537796I8268J0D01*
G01X521260D02*
G03X537796I8268J0D01*
G01D02*
G03X521260I-8268J0D01*
G01D02*
G03X537796I8268J0D01*
G01D02*
G03X521260I-8268J0D01*
G01X471265Y978747D02*
Y961424D01*
G01X539370Y-19685D02*
G03X547244Y-11811I0J7874D01*
G01X535433Y-7874D02*
X547244D01*
G01X535433Y0D02*
G03Y-7874I0J-3937D01*
G01X547244D02*
Y-11811D01*
G01Y3937D02*
Y57874D01*
G01X543307Y0D02*
G03X547244Y3937I0J3937D01*
G01X535433Y69685D02*
G03Y61811I0J-3937D01*
G01X547244Y73622D02*
Y127559D01*
G01X543307Y69685D02*
G03X547244Y73622I0J3937D01*
G01Y57874D02*
G03X543307Y61811I-3937J0D01*
G01X543875Y33722D02*
X580075D01*
G01X532195Y41867D02*
X535730Y45402D01*
G01X535433Y139370D02*
G03Y131496I0J-3937D01*
G01X547244Y143307D02*
Y197244D01*
G01X543307Y139370D02*
G03X547244Y143307I0J3937D01*
G01Y127559D02*
G03X543307Y131496I-3937J0D01*
G01X535433Y278740D02*
G03Y270866I0J-3937D01*
G01Y209055D02*
G03Y201181I0J-3937D01*
G01X543307Y278740D02*
G03X547244Y282677I0J3937D01*
G01Y212992D02*
Y266929D01*
G01X543307Y209055D02*
G03X547244Y212992I0J3937D01*
G01Y266929D02*
G03X543307Y270866I-3937J0D01*
G01X547244Y197244D02*
G03X543307Y201181I-3937J0D01*
G01X535433Y348425D02*
G03Y340551I0J-3937D01*
G01X547244Y352362D02*
Y406299D01*
G01X543307Y348425D02*
G03X547244Y352362I0J3937D01*
G01Y282677D02*
Y336614D01*
G01D02*
G03X543307Y340551I-3937J0D01*
G01X535433Y418110D02*
G03Y410236I0J-3937D01*
G01X547244Y422047D02*
Y475984D01*
G01X543307Y418110D02*
G03X547244Y422047I0J3937D01*
G01Y406299D02*
G03X543307Y410236I-3937J0D01*
G01X535433Y487795D02*
G03Y479921I0J-3937D01*
G01X547244Y491732D02*
Y545669D01*
G01X543307Y487795D02*
G03X547244Y491732I0J3937D01*
G01Y475984D02*
G03X543307Y479921I-3937J0D01*
G01X535433Y557480D02*
G03Y549606I0J-3937D01*
G01X547244Y561417D02*
Y615354D01*
G01X543307Y557480D02*
G03X547244Y561417I0J3937D01*
G01Y545669D02*
G03X543307Y549606I-3937J0D01*
G01X547244Y685285D02*
Y719159D01*
G01X535433Y627165D02*
G03Y619291I0J-3937D01*
G01X547244Y631102D02*
Y685039D01*
G01X543307Y627165D02*
G03X547244Y631102I0J3937D01*
G01Y685039D02*
G03X543307Y688976I-3937J0D01*
G01X547244Y615354D02*
G03X543307Y619291I-3937J0D01*
G01X644492Y-381883D02*
Y-399206D01*
G01Y978747D02*
Y961424D01*
G01X768902Y-366135D02*
Y-110229D01*
G01X1713784Y-305871D02*
X768902D01*
G01Y-366135D02*
X1713784D01*
G01X768902Y-260745D02*
X1300129D01*
G01X768902Y-170494D02*
X1713784D01*
G01X768902Y-215620D02*
X1713784D01*
G01X768902Y-110229D02*
X1713784D01*
G01X817721Y-381883D02*
Y-399206D01*
G01Y978747D02*
Y961424D01*
G01X990950Y-381883D02*
Y-399206D01*
G01X957879Y-305871D02*
Y-110350D01*
G01X1026202Y171908D02*
Y176293D01*
G01X1019706Y175318D02*
X1026202Y171908D01*
G01X1028368Y175318D02*
X1019706D01*
G01X1027646Y187986D02*
X1026924Y187499D01*
G01Y191396D02*
X1027646Y190909D01*
G01X1025481Y191883D02*
X1026924Y191396D01*
G01X1024037D02*
X1025481Y191883D01*
G01X1023315Y190909D02*
X1024037Y191396D01*
G01X1022594Y189934D02*
X1023315Y190909D01*
G01X1022594Y188960D02*
Y189934D01*
G01X1023315Y187986D02*
X1022594Y188960D01*
G01X1019706Y188473D02*
X1023315Y187986D01*
G01X1019706Y191396D02*
Y188473D01*
G01X1020428Y196268D02*
X1019706Y197243D01*
G01X1021150Y195781D02*
X1020428Y196268D01*
G01X1022594Y195294D02*
X1021150Y195781D01*
G01X1025481Y195294D02*
X1022594D01*
G01X1026924Y195781D02*
X1025481Y195294D01*
G01X1027646Y196268D02*
X1026924Y195781D01*
G01X1009929Y157340D02*
X1010651Y156366D01*
G01X1009208Y157827D02*
X1009929Y157340D01*
G01X1007764Y158314D02*
X1009208Y157827D01*
G01X1004877Y158314D02*
X1007764D01*
G01X1003433Y157827D02*
X1004877Y158314D01*
G01X1002712Y157340D02*
X1003433Y157827D01*
G01X1001990Y156366D02*
X1002712Y157340D01*
G01Y155391D02*
X1001990Y156366D01*
G01X1003433Y154904D02*
X1002712Y155391D01*
G01X1004877Y154417D02*
X1003433Y154904D01*
G01X1007764Y154417D02*
X1004877D01*
G01X1009208Y154904D02*
X1007764Y154417D01*
G01X1009929Y155391D02*
X1009208Y154904D01*
G01X1010651Y156366D02*
X1009929Y155391D01*
G01Y163674D02*
X1010651Y164161D01*
G01Y163674D02*
X1009929D01*
G01X1010651Y164161D02*
Y163674D01*
G01X1009929Y172930D02*
X1010651Y171956D01*
G01X1009208Y173418D02*
X1009929Y172930D01*
G01X1007764Y173905D02*
X1009208Y173418D01*
G01X1004877Y173905D02*
X1007764D01*
G01X1003433Y173418D02*
X1004877Y173905D01*
G01X1002712Y172930D02*
X1003433Y173418D01*
G01X1001990Y171956D02*
X1002712Y172930D01*
G01Y170982D02*
X1001990Y171956D01*
G01X1003433Y170495D02*
X1002712Y170982D01*
G01X1004877Y170007D02*
X1003433Y170495D01*
G01X1007764Y170007D02*
X1004877D01*
G01X1009208Y170495D02*
X1007764Y170007D01*
G01X1009929Y170982D02*
X1009208Y170495D01*
G01X1010651Y171956D02*
X1009929Y170982D01*
G01Y180726D02*
X1010651Y179751D01*
G01X1009208Y181213D02*
X1009929Y180726D01*
G01X1007764Y181700D02*
X1009208Y181213D01*
G01X1004877Y181700D02*
X1007764D01*
G01X1003433Y181213D02*
X1004877Y181700D01*
G01X1002712Y180726D02*
X1003433Y181213D01*
G01X1001990Y179751D02*
X1002712Y180726D01*
G01Y178777D02*
X1001990Y179751D01*
G01X1003433Y178290D02*
X1002712Y178777D01*
G01X1004877Y177803D02*
X1003433Y178290D01*
G01X1007764Y177803D02*
X1004877D01*
G01X1009208Y178290D02*
X1007764Y177803D01*
G01X1009929Y178777D02*
X1009208Y178290D01*
G01X1010651Y179751D02*
X1009929Y178777D01*
G01X1012816Y211621D02*
Y187980D01*
G01X1026924Y198704D02*
X1027646Y198217D01*
G01X1025481Y199192D02*
X1026924Y198704D01*
G01X1022594Y199192D02*
X1025481D01*
G01X1021150Y198704D02*
X1022594Y199192D01*
G01X1020428Y198217D02*
X1021150Y198704D01*
G01X1019706Y197243D02*
X1020428Y198217D01*
G01X972158Y234193D02*
X971671Y234914D01*
G01X973133Y233471D02*
X972158Y234193D01*
G01X974107Y233471D02*
X973133D01*
G01X975081Y234193D02*
X974107Y233471D01*
G01X975569Y234914D02*
X975081Y234193D01*
G01X976056Y236358D02*
X975569Y234914D01*
G01Y237802D02*
X976056Y236358D01*
G01X975081Y238523D02*
X975569Y237802D01*
G01X974107Y239245D02*
X975081Y238523D01*
G01X973133Y239245D02*
X974107D01*
G01X972158Y238523D02*
X973133Y239245D01*
G01X972646Y242132D02*
X972158Y238523D01*
G01X975569Y242132D02*
X972646D01*
G01X980928Y234193D02*
X981415Y233471D01*
G01X980928D02*
Y234193D01*
G01X981415Y233471D02*
X980928D01*
G01X990185Y234193D02*
X989211Y233471D01*
G01X990672Y234914D02*
X990185Y234193D01*
G01X991159Y236358D02*
X990672Y234914D01*
G01X991159Y239245D02*
Y236358D01*
G01X990672Y240689D02*
X991159Y239245D01*
G01X990185Y241410D02*
X990672Y240689D01*
G01X989211Y242132D02*
X990185Y241410D01*
G01X988236D02*
X989211Y242132D01*
G01X987749Y240689D02*
X988236Y241410D01*
G01X987262Y239245D02*
X987749Y240689D01*
G01X987262Y236358D02*
Y239245D01*
G01X987749Y234914D02*
X987262Y236358D01*
G01X988236Y234193D02*
X987749Y234914D01*
G01X989211Y233471D02*
X988236Y234193D01*
G01X997980D02*
X997006Y233471D01*
G01X998467Y234914D02*
X997980Y234193D01*
G01X998955Y236358D02*
X998467Y234914D01*
G01X998955Y239245D02*
Y236358D01*
G01X998467Y240689D02*
X998955Y239245D01*
G01X997980Y241410D02*
X998467Y240689D01*
G01X997006Y242132D02*
X997980Y241410D01*
G01X996031D02*
X997006Y242132D01*
G01X995544Y240689D02*
X996031Y241410D01*
G01X995057Y239245D02*
X995544Y240689D01*
G01X995057Y236358D02*
Y239245D01*
G01X995544Y234914D02*
X995057Y236358D01*
G01X996031Y234193D02*
X995544Y234914D01*
G01X997006Y233471D02*
X996031Y234193D01*
G01X1026596Y231306D02*
X1005234D01*
G01X974594Y214508D02*
X973620Y213786D01*
G01X975081Y215229D02*
X974594Y214508D01*
G01X975569Y216673D02*
X975081Y215229D01*
G01X975569Y219560D02*
Y216673D01*
G01X975081Y221004D02*
X975569Y219560D01*
G01X974594Y221725D02*
X975081Y221004D01*
G01X973620Y222447D02*
X974594Y221725D01*
G01X972646D02*
X973620Y222447D01*
G01X972158Y221004D02*
X972646Y221725D01*
G01X971671Y219560D02*
X972158Y221004D01*
G01X971671Y216673D02*
Y219560D01*
G01X972158Y215229D02*
X971671Y216673D01*
G01X972646Y214508D02*
X972158Y215229D01*
G01X973620Y213786D02*
X972646Y214508D01*
G01X980928D02*
X981415Y213786D01*
G01X980928D02*
Y214508D01*
G01X981415Y213786D02*
X980928D01*
G01X990185Y214508D02*
X989211Y213786D01*
G01X990672Y215229D02*
X990185Y214508D01*
G01X991159Y216673D02*
X990672Y215229D01*
G01X991159Y219560D02*
Y216673D01*
G01X990672Y221004D02*
X991159Y219560D01*
G01X990185Y221725D02*
X990672Y221004D01*
G01X989211Y222447D02*
X990185Y221725D01*
G01X988236D02*
X989211Y222447D01*
G01X987749Y221004D02*
X988236Y221725D01*
G01X987262Y219560D02*
X987749Y221004D01*
G01X987262Y216673D02*
Y219560D01*
G01X987749Y215229D02*
X987262Y216673D01*
G01X988236Y214508D02*
X987749Y215229D01*
G01X989211Y213786D02*
X988236Y214508D01*
G01X997980D02*
X997006Y213786D01*
G01X998467Y215229D02*
X997980Y214508D01*
G01X998955Y216673D02*
X998467Y215229D01*
G01X998955Y219560D02*
Y216673D01*
G01X998467Y221004D02*
X998955Y219560D01*
G01X997980Y221725D02*
X998467Y221004D01*
G01X997006Y222447D02*
X997980Y221725D01*
G01X996031D02*
X997006Y222447D01*
G01X995544Y221004D02*
X996031Y221725D01*
G01X995057Y219560D02*
X995544Y221004D01*
G01X995057Y216673D02*
Y219560D01*
G01X995544Y215229D02*
X995057Y216673D01*
G01X996031Y214508D02*
X995544Y215229D01*
G01X997006Y213786D02*
X996031Y214508D01*
G01X1012816Y211621D02*
X1005234D01*
G01X1023939Y222841D02*
X1023446D01*
G01D02*
Y218904D01*
G01D02*
X1023939D01*
G01D02*
Y220495D01*
G01D02*
X1026235D01*
G01D02*
Y218904D01*
G01D02*
X1026728D01*
G01D02*
Y222841D01*
G01D02*
X1026235D01*
G01D02*
Y220998D01*
G01D02*
X1023939D01*
G01D02*
Y222841D01*
G01X1046281Y231306D02*
G03X1014785I-15748J0D01*
G01D02*
G03X1046281I15748J0D01*
G01X1186045Y273432D02*
X1016753D01*
G01D02*
G03X1012816Y269495I0J-3937D01*
G01D02*
Y215558D01*
G01D02*
G03X1016753Y211621I3937J0D01*
G01D02*
X1186045D01*
G01X1020889Y229337D02*
G03X1028565Y221662I9644J1969D01*
G01X1020889Y229337D02*
X1014909D01*
G01Y233274D02*
X1020889D01*
G01X1028565Y240949D02*
G03X1020889Y233274I1968J-9644D01*
G01X1020691Y231306D02*
G03X1040376I9842J0D01*
G01D02*
G03X1020691I-9843J0D01*
G01X1014785D02*
G03X1014909Y229337I15741J3D01*
G01Y233274D02*
G03X1014785Y231306I15624J-1972D01*
G01X1038801D02*
G03X1022265I-8268J0D01*
G01D02*
G03X1038801I8268J0D01*
G01X1020889Y229337D02*
G03X1028565Y221662I9644J1969D01*
G01X1014909Y229337D02*
G03X1028565Y215681I15624J1968D01*
G01X1020889Y229337D02*
X1014909D01*
G01X1028565Y240949D02*
G03X1020889Y233274I1968J-9644D01*
G01X1014909D02*
X1020889D01*
G01X1028565Y246930D02*
G03X1014909Y233274I1968J-15624D01*
G01X1018468Y224908D02*
G03X1020436I984J0D01*
G01D02*
G03X1018468I-984J0D01*
G01X1023151Y220225D02*
G03X1025120I985J0D01*
G01D02*
G03X1023151I-985J0D01*
G01X1018468Y237703D02*
G03X1020436I984J0D01*
G01D02*
G03X1018468I-984J0D01*
G01X1023151Y242386D02*
G03X1025120I985J0D01*
G01D02*
G03X1023151I-985J0D01*
G01X1018468Y224908D02*
G03X1020436I984J0D01*
G01D02*
G03X1018468I-984J0D01*
G01X1023151Y220225D02*
G03X1025120I985J0D01*
G01D02*
G03X1023151I-985J0D01*
G01X1018468Y237703D02*
G03X1020436I984J0D01*
G01D02*
G03X1018468I-984J0D01*
G01X1023151Y242386D02*
G03X1025120I985J0D01*
G01D02*
G03X1023151I-985J0D01*
G01X1014785Y231306D02*
G03X1046281I15748J0D01*
G01D02*
G03X1014785I-15748J0D01*
G01X1038801D02*
G03X1022265I-8268J0D01*
G01D02*
G03X1038801I8268J0D01*
G01D02*
G03X1022265I-8268J0D01*
G01D02*
G03X1038801I8268J0D01*
G01X1018468Y224908D02*
G03X1020436I984J0D01*
G01D02*
G03X1018468I-984J0D01*
G01X1023151Y220225D02*
G03X1025120I985J0D01*
G01D02*
G03X1023151I-985J0D01*
G01X1018468Y237703D02*
G03X1020436I984J0D01*
G01D02*
G03X1018468I-984J0D01*
G01X1023151Y242386D02*
G03X1025120I985J0D01*
G01D02*
G03X1023151I-985J0D01*
G01X1020691Y231306D02*
G03X1040376I9842J0D01*
G01D02*
G03X1020691I-9843J0D01*
G01X1014785D02*
G03X1046281I15748J0D01*
G01D02*
G03X1014785I-15748J0D01*
G01X1018468Y224908D02*
G03X1020436I984J0D01*
G01D02*
G03X1018468I-984J0D01*
G01X1023151Y220225D02*
G03X1025120I985J0D01*
G01D02*
G03X1023151I-985J0D01*
G01X1018468Y237703D02*
G03X1020436I984J0D01*
G01D02*
G03X1018468I-984J0D01*
G01X1023151Y242386D02*
G03X1025120I985J0D01*
G01D02*
G03X1023151I-985J0D01*
G01X1038801Y231306D02*
G03X1022265I-8268J0D01*
G01D02*
G03X1038801I8268J0D01*
G01X1014785D02*
G03X1046281I15748J0D01*
G01D02*
G03X1014785I-15748J0D01*
G01X1022265D02*
G03X1038801I8268J0D01*
G01D02*
G03X1022265I-8268J0D01*
G01X1186045Y273432D02*
X1016753D01*
G01D02*
G03X1012816Y269495I0J-3937D01*
G01D02*
Y215558D01*
G01D02*
G03X1016753Y211621I3937J0D01*
G01D02*
X1186045D01*
G01X1022265Y231306D02*
G03X1038801I8268J0D01*
G01D02*
G03X1022265I-8268J0D01*
G01X1016753Y211621D02*
X1186045D01*
G01X1012816Y215558D02*
G03X1016753Y211621I3937J0D01*
G01X1012816Y269495D02*
Y215558D01*
G01X1016753Y273432D02*
G03X1012816Y269495I0J-3937D01*
G01X1186045Y273432D02*
X1016753D01*
G01X1005372Y428173D02*
X1004885Y428895D01*
G01X1005859Y427451D02*
X1005372Y428173D01*
G01X1006834Y426730D02*
X1005859Y427451D01*
G01X1007808Y426730D02*
X1006834D01*
G01X1008783Y427451D02*
X1007808Y426730D01*
G01X1009270Y428173D02*
X1008783Y427451D01*
G01X1009270Y429617D02*
Y428173D01*
G01X1008783Y430338D02*
X1009270Y429617D01*
G01X1007808Y431060D02*
X1008783Y430338D01*
G01X1006834Y431782D02*
X1007808Y431060D01*
G01X1005859Y432504D02*
X1006834Y431782D01*
G01X1005372Y433226D02*
X1005859Y432504D01*
G01X1005372Y433947D02*
Y433226D01*
G01X1005859Y434669D02*
X1005372Y433947D01*
G01X1006834Y435391D02*
X1005859Y434669D01*
G01X1007808Y435391D02*
X1006834D01*
G01X1008783Y434669D02*
X1007808Y435391D01*
G01X1009270Y433947D02*
X1008783Y434669D01*
G01X1016578D02*
X1017065Y433947D01*
G01X1015603Y435391D02*
X1016578Y434669D01*
G01X1014629Y435391D02*
X1015603D01*
G01X1013655Y434669D02*
X1014629Y435391D01*
G01X1013168Y433947D02*
X1013655Y434669D01*
G01X1012680Y433226D02*
X1013168Y433947D01*
G01X1012193Y431060D02*
X1012680Y433226D01*
G01Y428895D02*
X1012193Y431060D01*
G01X1013168Y428173D02*
X1012680Y428895D01*
G01X1013655Y427451D02*
X1013168Y428173D01*
G01X1014629Y426730D02*
X1013655Y427451D01*
G01X1015603Y426730D02*
X1014629D01*
G01X1016578Y427451D02*
X1015603Y426730D01*
G01X1017065Y428173D02*
X1016578Y427451D01*
G01X1022912Y435391D02*
X1025348Y426730D01*
G01X1020476D02*
X1022912Y435391D01*
G01X1021450Y429617D02*
X1024373D01*
G01X1012321Y445568D02*
X1181613D01*
G01X1008384Y449505D02*
G03X1012321Y445568I3937J0D01*
G01X1008384Y449505D02*
G03X1012321Y445568I3937J0D01*
G01D02*
X1181613D01*
G01X1012321D02*
X1181613D01*
G01X1008384Y449505D02*
G03X1012321Y445568I3937J0D01*
G01X1008384Y507379D02*
Y527863D01*
G01X1027260Y472458D02*
X1026878D01*
G01D02*
Y474951D01*
G01D02*
X1027260D01*
G01X1023903Y474561D02*
Y474016D01*
G01D02*
X1023979Y473549D01*
G01D02*
X1024285Y473081D01*
G01D02*
X1024514Y472925D01*
G01D02*
X1024895Y472847D01*
G01D02*
X1025276Y472925D01*
G01D02*
X1025505Y473081D01*
G01D02*
X1025810Y473549D01*
G01D02*
X1025887Y474016D01*
G01D02*
Y474561D01*
G01D02*
X1025810Y475029D01*
G01D02*
X1025505Y475496D01*
G01D02*
X1025276Y475652D01*
G01D02*
X1024895Y475730D01*
G01D02*
X1024514Y475652D01*
G01D02*
X1024285Y475496D01*
G01D02*
X1023979Y475029D01*
G01D02*
X1023903Y474561D01*
G01X1023598Y475029D02*
X1023522Y474639D01*
G01X1023674Y475262D02*
X1023598Y475029D01*
G01X1023827Y475574D02*
X1023674Y475262D01*
G01X1024056Y475808D02*
X1023827Y475574D01*
G01X1024437Y476042D02*
X1024056Y475808D01*
G01X1024895Y476119D02*
X1024437Y476042D01*
G01X1025353D02*
X1024895Y476119D01*
G01X1025734Y475808D02*
X1025353Y476042D01*
G01X1025963Y475574D02*
X1025734Y475808D01*
G01X1026115Y475262D02*
X1025963Y475574D01*
G01X1026192Y475029D02*
X1026115Y475262D01*
G01X1026268Y474639D02*
X1026192Y475029D01*
G01X1026268Y473938D02*
Y474639D01*
G01X1026192Y473549D02*
X1026268Y473938D01*
G01X1026115Y473315D02*
X1026192Y473549D01*
G01X1025963Y473003D02*
X1026115Y473315D01*
G01X1025734Y472769D02*
X1025963Y473003D01*
G01X1025353Y472536D02*
X1025734Y472769D01*
G01X1024895Y472458D02*
X1025353Y472536D01*
G01X1024437D02*
X1024895Y472458D01*
G01X1024056Y472769D02*
X1024437Y472536D01*
G01X1023827Y473003D02*
X1024056Y472769D01*
G01X1023674Y473315D02*
X1023827Y473003D01*
G01X1023598Y473549D02*
X1023674Y473315D01*
G01X1023522Y473938D02*
X1023598Y473549D01*
G01X1023522Y474639D02*
Y473938D01*
G01X1021691Y474016D02*
X1022912D01*
G01D02*
Y473705D01*
G01D02*
X1021691D01*
G01D02*
Y474016D01*
G01Y474951D02*
X1022912D01*
G01D02*
Y474639D01*
G01D02*
X1021691D01*
G01D02*
Y474951D01*
G01X1018487Y472458D02*
X1018030D01*
G01D02*
Y476119D01*
G01D02*
X1018487D01*
G01D02*
Y474639D01*
G01D02*
X1020623D01*
G01D02*
Y476119D01*
G01D02*
X1021081D01*
G01D02*
Y472458D01*
G01D02*
X1020623D01*
G01D02*
Y474172D01*
G01D02*
X1018487D01*
G01D02*
Y472458D01*
G01X1010353Y465253D02*
G03X1041849I15748J0D01*
G01D02*
G03X1010353I-15748J0D01*
G01X1181613Y507379D02*
X1012321D01*
G01X1008384Y503442D02*
Y449505D01*
G01X1012321Y507379D02*
G03X1008384Y503442I0J-3937D01*
G01X1024132Y449629D02*
Y455610D01*
G01X1016457Y463285D02*
G03X1024132Y455610I9644J1969D01*
G01X1016457Y463285D02*
X1010476D01*
G01Y467222D02*
X1016457D01*
G01X1024132Y474897D02*
G03X1016457Y467222I1969J-9644D01*
G01X1024132Y474897D02*
Y480878D01*
G01X1016258Y465253D02*
G03X1035943I9842J0D01*
G01D02*
G03X1016258I-9843J0D01*
G01X1024132Y449629D02*
G03X1028069I1968J15624D01*
G01X1010353Y465253D02*
G03X1010476Y463285I15748J-4D01*
G01X1028069Y480878D02*
G03X1024132I-1969J-15625D01*
G01X1010476Y467222D02*
G03X1010353Y465253I15625J-1964D01*
G01X1034368D02*
G03X1017833I-8268J0D01*
G01D02*
G03X1034368I8267J0D01*
G01X1016457Y463285D02*
G03X1024132Y455610I9644J1969D01*
G01Y449629D02*
Y455610D01*
G01X1010476Y463285D02*
G03X1024132Y449629I15625J1969D01*
G01X1016457Y463285D02*
X1010476D01*
G01X1024132Y474897D02*
G03X1016457Y467222I1969J-9644D01*
G01X1010476D02*
X1016457D01*
G01X1024132Y480878D02*
G03X1010476Y467222I1969J-15625D01*
G01X1024132Y474897D02*
Y480878D01*
G01X1014035Y458856D02*
G03X1016004I985J0D01*
G01D02*
G03X1014035I-985J0D01*
G01X1018719Y454172D02*
G03X1020687I984J0D01*
G01D02*
G03X1018719I-984J0D01*
G01X1014035Y471651D02*
G03X1016004I985J0D01*
G01D02*
G03X1014035I-985J0D01*
G01X1018719Y476334D02*
G03X1020687I984J0D01*
G01D02*
G03X1018719I-984J0D01*
G01X1014035Y458856D02*
G03X1016004I985J0D01*
G01D02*
G03X1014035I-985J0D01*
G01X1018719Y454172D02*
G03X1020687I984J0D01*
G01D02*
G03X1018719I-984J0D01*
G01X1014035Y471651D02*
G03X1016004I985J0D01*
G01D02*
G03X1014035I-985J0D01*
G01X1018719Y476334D02*
G03X1020687I984J0D01*
G01D02*
G03X1018719I-984J0D01*
G01X1010353Y465253D02*
G03X1041849I15748J0D01*
G01D02*
G03X1010353I-15748J0D01*
G01X1034368D02*
G03X1017833I-8268J0D01*
G01D02*
G03X1034368I8267J0D01*
G01D02*
G03X1017833I-8268J0D01*
G01D02*
G03X1034368I8267J0D01*
G01X1014035Y458856D02*
G03X1016004I985J0D01*
G01D02*
G03X1014035I-985J0D01*
G01X1018719Y454172D02*
G03X1020687I984J0D01*
G01D02*
G03X1018719I-984J0D01*
G01X1014035Y471651D02*
G03X1016004I985J0D01*
G01D02*
G03X1014035I-985J0D01*
G01X1018719Y476334D02*
G03X1020687I984J0D01*
G01D02*
G03X1018719I-984J0D01*
G01X1016258Y465253D02*
G03X1035943I9842J0D01*
G01D02*
G03X1016258I-9843J0D01*
G01X1010353D02*
G03X1041849I15748J0D01*
G01D02*
G03X1010353I-15748J0D01*
G01X1014035Y458856D02*
G03X1016004I985J0D01*
G01D02*
G03X1014035I-985J0D01*
G01X1018719Y454172D02*
G03X1020687I984J0D01*
G01D02*
G03X1018719I-984J0D01*
G01X1014035Y471651D02*
G03X1016004I985J0D01*
G01D02*
G03X1014035I-985J0D01*
G01X1018719Y476334D02*
G03X1020687I984J0D01*
G01D02*
G03X1018719I-984J0D01*
G01X1034368Y465253D02*
G03X1017833I-8268J0D01*
G01D02*
G03X1034368I8267J0D01*
G01X1010353D02*
G03X1041849I15748J0D01*
G01D02*
G03X1010353I-15748J0D01*
G01X1017833D02*
G03X1034368I8267J0D01*
G01D02*
G03X1017833I-8268J0D01*
G01X1181613Y507379D02*
X1012321D01*
G01D02*
G03X1008384Y503442I0J-3937D01*
G01D02*
Y449505D01*
G01X1017833Y465253D02*
G03X1034368I8267J0D01*
G01D02*
G03X1017833I-8268J0D01*
G01X1008384Y503442D02*
Y449505D01*
G01X1012321Y507379D02*
G03X1008384Y503442I0J-3937D01*
G01X1181613Y507379D02*
X1012321D01*
G01X1005497Y537066D02*
X1006219Y536091D01*
G01X1004775Y537553D02*
X1005497Y537066D01*
G01X1003332Y538040D02*
X1004775Y537553D01*
G01X1000444Y538040D02*
X1003332D01*
G01X999001Y537553D02*
X1000444Y538040D01*
G01X998279Y537066D02*
X999001Y537553D01*
G01X997557Y536091D02*
X998279Y537066D01*
G01Y535117D02*
X997557Y536091D01*
G01X999001Y534629D02*
X998279Y535117D01*
G01X1000444Y534142D02*
X999001Y534629D01*
G01X1003332Y534142D02*
X1000444D01*
G01X1004775Y534629D02*
X1003332Y534142D01*
G01X1005497Y535117D02*
X1004775Y534629D01*
G01X1006219Y536091D02*
X1005497Y535117D01*
G01Y543399D02*
X1006219Y543886D01*
G01Y543399D02*
X1005497D01*
G01X1006219Y543886D02*
Y543399D01*
G01X1005497Y552656D02*
X1006219Y551682D01*
G01X1004775Y553143D02*
X1005497Y552656D01*
G01X1003332Y553630D02*
X1004775Y553143D01*
G01X1000444Y553630D02*
X1003332D01*
G01X999001Y553143D02*
X1000444Y553630D01*
G01X998279Y552656D02*
X999001Y553143D01*
G01X997557Y551682D02*
X998279Y552656D01*
G01Y550707D02*
X997557Y551682D01*
G01X999001Y550220D02*
X998279Y550707D01*
G01X1000444Y549733D02*
X999001Y550220D01*
G01X1003332Y549733D02*
X1000444D01*
G01X1004775Y550220D02*
X1003332Y549733D01*
G01X1005497Y550707D02*
X1004775Y550220D01*
G01X1006219Y551682D02*
X1005497Y550707D01*
G01Y560451D02*
X1006219Y559477D01*
G01X1004775Y560938D02*
X1005497Y560451D01*
G01X1003332Y561426D02*
X1004775Y560938D01*
G01X1000444Y561426D02*
X1003332D01*
G01X999001Y560938D02*
X1000444Y561426D01*
G01X998279Y560451D02*
X999001Y560938D01*
G01X997557Y559477D02*
X998279Y560451D01*
G01Y558503D02*
X997557Y559477D01*
G01X999001Y558015D02*
X998279Y558503D01*
G01X1000444Y557528D02*
X999001Y558015D01*
G01X1003332Y557528D02*
X1000444D01*
G01X1004775Y558015D02*
X1003332Y557528D01*
G01X1005497Y558503D02*
X1004775Y558015D01*
G01X1006219Y559477D02*
X1005497Y558503D01*
G01X990950Y978747D02*
Y961424D01*
G01X1070070Y113617D02*
X1069583Y114339D01*
G01X1070557Y112895D02*
X1070070Y113617D01*
G01X1071531Y112895D02*
X1070557D01*
G01X1072018Y113617D02*
X1071531Y112895D01*
G01X1072506Y114339D02*
X1072018Y113617D01*
G01X1077865D02*
X1076891Y115060D01*
G01X1078839Y112895D02*
X1077865Y113617D01*
G01X1079814D02*
X1078839Y112895D01*
G01X1080788Y115060D02*
X1079814Y113617D01*
G01X1093455D02*
X1092481Y115060D01*
G01X1094430Y112895D02*
X1093455Y113617D01*
G01X1095404D02*
X1094430Y112895D01*
G01X1096379Y115060D02*
X1095404Y113617D01*
G01X1101251D02*
X1100276Y115060D01*
G01X1102225Y112895D02*
X1101251Y113617D01*
G01X1103200D02*
X1102225Y112895D01*
G01X1103687Y114339D02*
X1103200Y113617D01*
G01X1108559Y112895D02*
Y118669D01*
G01X1096379Y121556D02*
Y112895D01*
G01X1086635D02*
Y121556D01*
G01X1027646Y181165D02*
X1028368Y181652D01*
G01Y181165D02*
X1027646D01*
G01X1028368Y181652D02*
Y181165D01*
G01Y188960D02*
X1027646Y187986D01*
G01X1028368Y189934D02*
Y188960D01*
G01X1027646Y190909D02*
X1028368Y189934D01*
G01Y197243D02*
X1027646Y196268D01*
G01X1072506Y115060D02*
Y114339D01*
G01X1072018Y115782D02*
X1072506Y115060D01*
G01X1071044Y116504D02*
X1072018Y115782D01*
G01X1070070Y117226D02*
X1071044Y116504D01*
G01X1070070Y117948D02*
Y117226D01*
G01X1070557Y118669D02*
X1070070Y117948D01*
G01X1071531Y118669D02*
X1070557D01*
G01X1072018Y117948D02*
X1071531Y118669D01*
G01X1080788Y116504D02*
Y115060D01*
G01X1079814Y117948D02*
X1080788Y116504D01*
G01X1078839Y118669D02*
X1079814Y117948D01*
G01X1077865D02*
X1078839Y118669D01*
G01X1076891Y116504D02*
X1077865Y117948D01*
G01X1076891Y115060D02*
Y116504D01*
G01X1095404Y117948D02*
X1096379Y116504D01*
G01X1094430Y118669D02*
X1095404Y117948D01*
G01X1093455D02*
X1094430Y118669D01*
G01X1092481Y116504D02*
X1093455Y117948D01*
G01X1092481Y115060D02*
Y116504D01*
G01X1103687D02*
X1100276D01*
G01X1103200Y117948D02*
X1103687Y116504D01*
G01X1102225Y118669D02*
X1103200Y117948D01*
G01X1101251D02*
X1102225Y118669D01*
G01X1100276Y116504D02*
X1101251Y117948D01*
G01X1100276Y115060D02*
Y116504D01*
G01X1109533Y118669D02*
X1110508D01*
G01X1108559Y117226D02*
X1109533Y118669D01*
G01X1095493Y234849D02*
X1075808D01*
G01X1077580Y233471D02*
X1093721D01*
G01X1093525Y233274D02*
X1077776D01*
G01X1058336Y225163D02*
X1058467Y225191D01*
G01X1062273Y225163D02*
X1062404Y225191D01*
G01X1057847Y224220D02*
X1057715Y224192D01*
G01X1066210Y225163D02*
X1066341Y225191D01*
G01X1061784Y224220D02*
X1061652Y224192D01*
G01X1070147Y225163D02*
X1070278Y225191D01*
G01X1065721Y224220D02*
X1065589Y224192D01*
G01X1074084Y225163D02*
X1074215Y225191D01*
G01X1069658Y224220D02*
X1069526Y224192D01*
G01X1074282Y227172D02*
X1074676Y227565D01*
G01X1070345Y227172D02*
X1070739Y227565D01*
G01X1053367Y230715D02*
X1052580D01*
G01X1053170Y230518D02*
X1052776D01*
G01X1053367Y230420D02*
X1052580D01*
G01Y230321D02*
X1053367D01*
G01X1077580Y230125D02*
X1051399D01*
G01X1052540Y229810D02*
X1054115D01*
G01X1054942Y228943D02*
X1077580D01*
G01X1052225Y228747D02*
X1051399D01*
G01X1053406D02*
X1052540D01*
G01X1117580D02*
X1053721D01*
G01X1053367Y228550D02*
X1052580D01*
G01X1053406Y228432D02*
X1052540D01*
G01X1053367Y227754D02*
X1052580D01*
G01Y227574D02*
X1053367D01*
G01X1058928Y227565D02*
X1057255D01*
G01X1062865D02*
X1061192D01*
G01X1066802D02*
X1065129D01*
G01X1070739D02*
X1069066D01*
G01X1074676D02*
X1073003D01*
G01X1078613D02*
X1076940D01*
G01X1077334Y227172D02*
X1078219D01*
G01X1073397D02*
X1074282D01*
G01X1069460D02*
X1070345D01*
G01X1065523D02*
X1066408D01*
G01X1061586D02*
X1062471D01*
G01X1057649D02*
X1058534D01*
G01X1052580Y227119D02*
X1053367D01*
G01Y227021D02*
X1052580D01*
G01Y226975D02*
X1054942D01*
G01X1055139Y226778D02*
X1053564D01*
G01X1077383Y226660D02*
X1078170D01*
G01X1073446D02*
X1074233D01*
G01X1069509D02*
X1070296D01*
G01X1065572D02*
X1066359D01*
G01X1061635D02*
X1062422D01*
G01X1057698D02*
X1058485D01*
G01X1053139Y226384D02*
X1052807D01*
G01X1058485Y226211D02*
X1057698D01*
G01X1062422D02*
X1061635D01*
G01X1066359D02*
X1065572D01*
G01X1070296D02*
X1069509D01*
G01X1074233D02*
X1073446D01*
G01X1078170D02*
X1077383D01*
G01X1058485Y226139D02*
X1057698D01*
G01X1062422D02*
X1061635D01*
G01X1066359D02*
X1065572D01*
G01X1070296D02*
X1069509D01*
G01X1074233D02*
X1073446D01*
G01X1078170D02*
X1077383D01*
G01X1074282Y225991D02*
X1077334D01*
G01X1070345D02*
X1073397D01*
G01X1066408D02*
X1069460D01*
G01X1062471D02*
X1065523D01*
G01X1058534D02*
X1061586D01*
G01X1055729D02*
X1057649D01*
G01X1052540D02*
X1054115D01*
G01X1058534Y225873D02*
X1057649D01*
G01X1062471D02*
X1061586D01*
G01X1066408D02*
X1065523D01*
G01X1070345D02*
X1069460D01*
G01X1074282D02*
X1073397D01*
G01X1078219D02*
X1077334D01*
G01X1077383Y225676D02*
X1078170D01*
G01X1073446D02*
X1074233D01*
G01X1069509D02*
X1070296D01*
G01X1065572D02*
X1066359D01*
G01X1061635D02*
X1062422D01*
G01X1057698D02*
X1058485D01*
G01X1077580Y225597D02*
X1077973D01*
G01X1073643D02*
X1074036D01*
G01X1069706D02*
X1070099D01*
G01X1065769D02*
X1066162D01*
G01X1061832D02*
X1062225D01*
G01X1057895D02*
X1058288D01*
G01X1058534Y225479D02*
X1057649D01*
G01X1062471D02*
X1061586D01*
G01X1066408D02*
X1065523D01*
G01X1070345D02*
X1069460D01*
G01X1074282D02*
X1073397D01*
G01X1078219D02*
X1077334D01*
G01X1053367Y225400D02*
X1052580D01*
G01X1077532Y225163D02*
X1078021D01*
G01X1073595D02*
X1074084D01*
G01X1069658D02*
X1070147D01*
G01X1065721D02*
X1066210D01*
G01X1061784D02*
X1062273D01*
G01X1057847D02*
X1058336D01*
G01X1053406Y224810D02*
X1052540D01*
G01X1053367Y224793D02*
X1052580D01*
G01Y224613D02*
X1053367D01*
G01X1073595Y224220D02*
X1073463Y224192D01*
G01X1077532Y224220D02*
X1077400Y224192D01*
G01X1066408Y227172D02*
X1066802Y227565D01*
G01X1054942Y219298D02*
X1055139Y219495D01*
G01X1062471Y227172D02*
X1062865Y227565D01*
G01X1077776Y230439D02*
X1077580Y230125D01*
G01X1077855Y224691D02*
X1077871Y224748D01*
X1077884Y224801D01*
X1077893Y224851D01*
G01X1077776Y233274D02*
X1077580Y233471D01*
G01X1077400Y225191D02*
X1077532Y225163D01*
G01X1073463Y225191D02*
X1073595Y225163D01*
G01X1069526Y225191D02*
X1069658Y225163D01*
G01X1074215Y224192D02*
X1074084Y224220D01*
G01X1058288Y224416D02*
X1057895D01*
G01X1062225D02*
X1061832D01*
G01X1066162D02*
X1065769D01*
G01X1070099D02*
X1069706D01*
G01X1074036D02*
X1073643D01*
G01X1077973D02*
X1077580D01*
G01X1058336Y224220D02*
X1057847D01*
G01X1062273D02*
X1061784D01*
G01X1066210D02*
X1065721D01*
G01X1070147D02*
X1069658D01*
G01X1074084D02*
X1073595D01*
G01X1078021D02*
X1077532D01*
G01X1053564Y224022D02*
X1055139D01*
G01X1057649D02*
X1055729D01*
G01X1061586D02*
X1058534D01*
G01X1065523D02*
X1062471D01*
G01X1069460D02*
X1066408D01*
G01X1073397D02*
X1070345D01*
G01X1077334D02*
X1074282D01*
G01X1058485Y223904D02*
X1057698D01*
G01X1062422D02*
X1061635D01*
G01X1066359D02*
X1065572D01*
G01X1070296D02*
X1069509D01*
G01X1074233D02*
X1073446D01*
G01X1078170D02*
X1077383D01*
G01Y223874D02*
X1078170D01*
G01X1073446D02*
X1074233D01*
G01X1069509D02*
X1070296D01*
G01X1065572D02*
X1066359D01*
G01X1061635D02*
X1062422D01*
G01X1057698D02*
X1058485D01*
G01X1054942Y223825D02*
X1053367D01*
G01X1077383Y223802D02*
X1078170D01*
G01X1073446D02*
X1074233D01*
G01X1069509D02*
X1070296D01*
G01X1065572D02*
X1066359D01*
G01X1061635D02*
X1062422D01*
G01X1057698D02*
X1058485D01*
G01X1053367Y223773D02*
X1052580D01*
G01X1058534Y223747D02*
X1057649D01*
G01X1062471D02*
X1061586D01*
G01X1066408D02*
X1065523D01*
G01X1070345D02*
X1069460D01*
G01X1074282D02*
X1073397D01*
G01X1078219D02*
X1077334D01*
G01X1058485Y223707D02*
X1057698D01*
G01X1062422D02*
X1061635D01*
G01X1066359D02*
X1065572D01*
G01X1070296D02*
X1069509D01*
G01X1074233D02*
X1073446D01*
G01X1078170D02*
X1077383D01*
G01X1053367Y223602D02*
X1052580D01*
G01Y223589D02*
X1053367D01*
G01X1073397Y223353D02*
X1074282D01*
G01X1069460D02*
X1070345D01*
G01X1061586D02*
X1062471D01*
G01X1058534D02*
X1057649D01*
G01X1066408D02*
X1065523D01*
G01X1078219D02*
X1077334D01*
G01X1053367Y223243D02*
X1052580D01*
G01X1053139Y222447D02*
X1052807D01*
G01X1052225Y222172D02*
X1054115D01*
G01X1052540Y222054D02*
X1054115D01*
G01X1058534Y222014D02*
X1057649D01*
G01X1062471D02*
X1061586D01*
G01X1066408D02*
X1065523D01*
G01X1070345D02*
X1069460D01*
G01X1074282D02*
X1073397D01*
G01X1078219D02*
X1077334D01*
G01X1058485Y221880D02*
X1057698D01*
G01X1062422D02*
X1061635D01*
G01X1066359D02*
X1065572D01*
G01X1070296D02*
X1069509D01*
G01X1074233D02*
X1073446D01*
G01X1078170D02*
X1077383D01*
G01X1054115Y221857D02*
X1052540D01*
G01X1058485Y221808D02*
X1057698D01*
G01X1062422D02*
X1061635D01*
G01X1066359D02*
X1065572D01*
G01X1070296D02*
X1069509D01*
G01X1074233D02*
X1073446D01*
G01X1078170D02*
X1077383D01*
G01Y221660D02*
X1078170D01*
G01X1074282D02*
X1077334D01*
G01X1073446D02*
X1074233D01*
G01X1070345D02*
X1073397D01*
G01X1069509D02*
X1070296D01*
G01X1066408D02*
X1069460D01*
G01X1065572D02*
X1066359D01*
G01X1062471D02*
X1065523D01*
G01X1061635D02*
X1062422D01*
G01X1058534D02*
X1061586D01*
G01X1057698D02*
X1058485D01*
G01X1055729D02*
X1057649D01*
G01X1058534Y221621D02*
X1057649D01*
G01X1062471D02*
X1061586D01*
G01X1066408D02*
X1065523D01*
G01X1070345D02*
X1069460D01*
G01X1074282D02*
X1073397D01*
G01X1078219D02*
X1077334D01*
G01X1058485Y221463D02*
X1057698D01*
G01X1062422D02*
X1061635D01*
G01X1066359D02*
X1065572D01*
G01X1070296D02*
X1069509D01*
G01X1074233D02*
X1073446D01*
G01X1078170D02*
X1077383D01*
G01X1077580Y221266D02*
X1077973D01*
G01X1073643D02*
X1074036D01*
G01X1069706D02*
X1070099D01*
G01X1065769D02*
X1066162D01*
G01X1061832D02*
X1062225D01*
G01X1057895D02*
X1058288D01*
G01X1077383Y221092D02*
X1078170D01*
G01X1073446D02*
X1074233D01*
G01X1069509D02*
X1070296D01*
G01X1065572D02*
X1066359D01*
G01X1061635D02*
X1062422D01*
G01X1057698D02*
X1058485D01*
G01X1052540Y220873D02*
X1054115D01*
G01X1053406Y220558D02*
X1052540D01*
G01Y220203D02*
X1053406D01*
G01X1058288Y220085D02*
X1057895D01*
G01X1062225D02*
X1061832D01*
G01X1066162D02*
X1065769D01*
G01X1070099D02*
X1069706D01*
G01X1074036D02*
X1073643D01*
G01X1077973D02*
X1077580D01*
G01X1052540Y219888D02*
X1054115D01*
G01X1077383Y219722D02*
X1078170D01*
G01X1073446D02*
X1074233D01*
G01X1069509D02*
X1070296D01*
G01X1065572D02*
X1066359D01*
G01X1061635D02*
X1062422D01*
G01X1057698D02*
X1058485D01*
G01X1057649Y219691D02*
X1055729D01*
G01X1061586D02*
X1058534D01*
G01X1065523D02*
X1062471D01*
G01X1069460D02*
X1066408D01*
G01X1073397D02*
X1070345D01*
G01X1077334D02*
X1074282D01*
G01X1077383Y219543D02*
X1078170D01*
G01X1073446D02*
X1074233D01*
G01X1069509D02*
X1070296D01*
G01X1065572D02*
X1066359D01*
G01X1061635D02*
X1062422D01*
G01X1057698D02*
X1058485D01*
G01X1071871Y219495D02*
X1116162D01*
G01X1063997D02*
X1067934D01*
G01X1055139D02*
X1060060D01*
G01X1062471D02*
X1061586D01*
G01X1070345D02*
X1069460D01*
G01X1077383Y219471D02*
X1078170D01*
G01X1073446D02*
X1074233D01*
G01X1069509D02*
X1070296D01*
G01X1065572D02*
X1066359D01*
G01X1061635D02*
X1062422D01*
G01X1057698D02*
X1058485D01*
G01X1060060Y219298D02*
X1054942D01*
G01X1067934D02*
X1063997D01*
G01X1116359D02*
X1071871D01*
G01X1052540Y219101D02*
X1054115D01*
G01X1058534D02*
X1057649D01*
G01X1062471D02*
X1061586D01*
G01X1066408D02*
X1065523D01*
G01X1070345D02*
X1069460D01*
G01X1074282D02*
X1073397D01*
G01X1078219D02*
X1077334D01*
G01X1067934Y218707D02*
X1071871D01*
G01X1060060D02*
X1063997D01*
G01X1077383Y218588D02*
X1078170D01*
G01X1073446D02*
X1074233D01*
G01X1069509D02*
X1070296D01*
G01X1065572D02*
X1066359D01*
G01X1061635D02*
X1062422D01*
G01X1057698D02*
X1058485D01*
G01X1119902Y218510D02*
X1051399D01*
G01X1058534Y227172D02*
X1058928Y227565D01*
G01X1054942Y223825D02*
X1055139Y224022D01*
G01X1053367Y223825D02*
X1053564Y224022D01*
G01X1053721Y228747D02*
X1053406Y228432D01*
G01X1073918Y224691D02*
X1073934Y224748D01*
X1073947Y224801D01*
X1073956Y224851D01*
G01X1077698Y224691D02*
X1077682Y224635D01*
X1077669Y224582D01*
X1077660Y224532D01*
G01X1073761Y224691D02*
X1073745Y224635D01*
X1073732Y224582D01*
X1073723Y224532D01*
G01X1077973Y221266D02*
Y220085D01*
G01Y225597D02*
Y224416D01*
G01X1077893Y224851D02*
Y224532D01*
G01X1077776Y233274D02*
Y228747D01*
G01X1077660Y224532D02*
Y224851D01*
G01X1077580Y228943D02*
Y233471D01*
G01Y224416D02*
Y225597D01*
G01Y220085D02*
Y221266D01*
G01X1077400Y225191D02*
Y224192D01*
G01X1077383Y215361D02*
Y226660D01*
G01X1077334Y227172D02*
Y218510D01*
G01X1077893Y224532D02*
X1077884Y224582D01*
X1077871Y224635D01*
X1077855Y224691D01*
G01X1077660Y224851D02*
X1077669Y224801D01*
X1077682Y224748D01*
X1077698Y224691D01*
G01X1073956Y224532D02*
X1073947Y224582D01*
X1073934Y224635D01*
X1073918Y224691D01*
G01X1073723Y224851D02*
X1073732Y224801D01*
X1073745Y224748D01*
X1073761Y224691D01*
G01X1077580Y228943D02*
X1077776Y228747D01*
G01X1076940Y227565D02*
X1077334Y227172D01*
G01X1065589Y225191D02*
X1065721Y225163D01*
G01X1070278Y224192D02*
X1070147Y224220D01*
G01X1061652Y225191D02*
X1061784Y225163D01*
G01X1066341Y224192D02*
X1066210Y224220D01*
G01X1057715Y225191D02*
X1057847Y225163D01*
G01X1062404Y224192D02*
X1062273Y224220D01*
G01X1058467Y224192D02*
X1058336Y224220D01*
G01X1075217Y218117D02*
X1051399D01*
G01X1079154D02*
X1076399D01*
G01Y217723D02*
X1075217D01*
G01X1077383Y217386D02*
X1078170D01*
G01X1073446D02*
X1074233D01*
G01X1069509D02*
X1070296D01*
G01X1065572D02*
X1066359D01*
G01X1061635D02*
X1062422D01*
G01X1057698D02*
X1058485D01*
G01X1096084Y217329D02*
X1075217D01*
G01X1058485Y215951D02*
X1057698D01*
G01X1062422D02*
X1061635D01*
G01X1066359D02*
X1065572D01*
G01X1070296D02*
X1069509D01*
G01X1074233D02*
X1073446D01*
G01X1078170D02*
X1077383D01*
G01X1058485Y215361D02*
X1057698D01*
G01X1062422D02*
X1061635D01*
G01X1066359D02*
X1065572D01*
G01X1070296D02*
X1069509D01*
G01X1074233D02*
X1073446D01*
G01X1078170D02*
X1077383D01*
G01X1053721Y230125D02*
X1053406Y229810D01*
G01X1052776Y230518D02*
X1052580Y230321D01*
G01X1069981Y224691D02*
X1069997Y224748D01*
X1070010Y224801D01*
X1070019Y224851D01*
G01X1066044Y224691D02*
X1066060Y224748D01*
X1066073Y224801D01*
X1066082Y224851D01*
G01X1069824Y224691D02*
X1069808Y224635D01*
X1069795Y224582D01*
X1069786Y224532D01*
G01X1065887Y224691D02*
X1065871Y224635D01*
X1065858Y224582D01*
X1065849Y224532D01*
G01X1076940Y227565D02*
Y218510D01*
G01X1076399Y218117D02*
Y217723D01*
G01X1075808Y234849D02*
Y230125D01*
G01X1075217Y217329D02*
Y218117D01*
G01X1074676Y227565D02*
Y218510D01*
G01X1074282Y227172D02*
Y218510D01*
G01X1074233Y215361D02*
Y226660D01*
G01X1074215Y224192D02*
Y225191D01*
G01X1074036Y221266D02*
Y220085D01*
G01Y225597D02*
Y224416D01*
G01X1073956Y224851D02*
Y224532D01*
G01X1073723D02*
Y224851D01*
G01X1073643Y224416D02*
Y225597D01*
G01Y220085D02*
Y221266D01*
G01X1073463Y225191D02*
Y224192D01*
G01X1073446Y215361D02*
Y226660D01*
G01X1073397Y227172D02*
Y218510D01*
G01X1073003Y227565D02*
Y218510D01*
G01X1071871Y218707D02*
Y219495D01*
G01X1070019Y224532D02*
X1070010Y224582D01*
X1069997Y224635D01*
X1069981Y224691D01*
G01X1069786Y224851D02*
X1069795Y224801D01*
X1069808Y224748D01*
X1069824Y224691D01*
G01X1073003Y227565D02*
X1073397Y227172D01*
G01X1069066Y227565D02*
X1069460Y227172D01*
G01X1065129Y227565D02*
X1065523Y227172D01*
G01X1053367Y222841D02*
X1053139Y222447D01*
G01X1053367Y226778D02*
X1053139Y226384D01*
G01X1062107Y224691D02*
X1062123Y224748D01*
X1062136Y224801D01*
X1062145Y224851D01*
G01X1061950Y224691D02*
X1061934Y224635D01*
X1061921Y224582D01*
X1061912Y224532D01*
G01X1070739Y227565D02*
Y218510D01*
G01X1070345Y227172D02*
Y218510D01*
G01X1070296Y215361D02*
Y226660D01*
G01X1070278Y224192D02*
Y225191D01*
G01X1070099Y221266D02*
Y220085D01*
G01Y225597D02*
Y224416D01*
G01X1070019Y224851D02*
Y224532D01*
G01X1069786D02*
Y224851D01*
G01X1069706Y224416D02*
Y225597D01*
G01Y220085D02*
Y221266D01*
G01X1069526Y225191D02*
Y224192D01*
G01X1069509Y215361D02*
Y226660D01*
G01X1069460Y227172D02*
Y218510D01*
G01X1069066Y227565D02*
Y218510D01*
G01X1067934Y219495D02*
Y218707D01*
G01X1066802Y227565D02*
Y218510D01*
G01X1066408Y227172D02*
Y218510D01*
G01X1066359Y215361D02*
Y226660D01*
G01X1066341Y224192D02*
Y225191D01*
G01X1066162Y221266D02*
Y220085D01*
G01Y225597D02*
Y224416D01*
G01X1066082Y224851D02*
Y224532D01*
G01X1065849D02*
Y224851D01*
G01X1065769Y224416D02*
Y225597D01*
G01Y220085D02*
Y221266D01*
G01X1065589Y225191D02*
Y224192D01*
G01X1065572Y215361D02*
Y226660D01*
G01X1065523Y227172D02*
Y218510D01*
G01X1065129Y227565D02*
Y218510D01*
G01X1066082Y224532D02*
X1066073Y224582D01*
X1066060Y224635D01*
X1066044Y224691D01*
G01X1065849Y224851D02*
X1065858Y224801D01*
X1065871Y224748D01*
X1065887Y224691D01*
G01X1062145Y224532D02*
X1062136Y224582D01*
X1062123Y224635D01*
X1062107Y224691D01*
G01X1061912Y224851D02*
X1061921Y224801D01*
X1061934Y224748D01*
X1061950Y224691D01*
G01X1061192Y227565D02*
X1061586Y227172D01*
G01X1057255Y227565D02*
X1057649Y227172D01*
G01X1054942Y228943D02*
X1055139Y228747D01*
G01X1053367Y230321D02*
X1053170Y230518D01*
G01X1058170Y224691D02*
X1058186Y224748D01*
X1058199Y224801D01*
X1058208Y224851D01*
G01X1058013Y224691D02*
X1057997Y224635D01*
X1057984Y224582D01*
X1057975Y224532D01*
G01X1063997Y218707D02*
Y219495D01*
G01X1062865Y227565D02*
Y218510D01*
G01X1062471Y227172D02*
Y218510D01*
G01X1062422Y215361D02*
Y226660D01*
G01X1062404Y224192D02*
Y225191D01*
G01X1062225Y221266D02*
Y220085D01*
G01Y225597D02*
Y224416D01*
G01X1062145Y224851D02*
Y224532D01*
G01X1061912D02*
Y224851D01*
G01X1061832Y224416D02*
Y225597D01*
G01Y220085D02*
Y221266D01*
G01X1061652Y225191D02*
Y224192D01*
G01X1061635Y215361D02*
Y226660D01*
G01X1061586Y227172D02*
Y218510D01*
G01X1061192Y227565D02*
Y218510D01*
G01X1060060Y219495D02*
Y218707D01*
G01X1058928Y227565D02*
Y218510D01*
G01X1058534Y227172D02*
Y218510D01*
G01X1058485Y215361D02*
Y226660D01*
G01X1058467Y224192D02*
Y225191D01*
G01X1058208Y224532D02*
X1058199Y224582D01*
X1058186Y224635D01*
X1058170Y224691D01*
G01X1057975Y224851D02*
X1057984Y224801D01*
X1057997Y224748D01*
X1058013Y224691D01*
G01X1052540Y229810D02*
X1052225Y230125D01*
G01X1054942Y226975D02*
X1055139Y226778D01*
G01X1052540Y228432D02*
X1052225Y228747D01*
G01X1053367Y226975D02*
X1053564Y226778D01*
G01X1052540Y221857D02*
X1052225Y222172D01*
G01X1058288Y221266D02*
Y220085D01*
G01Y225597D02*
Y224416D01*
G01X1058208Y224851D02*
Y224532D01*
G01X1057975D02*
Y224851D01*
G01X1057895Y224416D02*
Y225597D01*
G01Y220085D02*
Y221266D01*
G01X1057715Y225191D02*
Y224192D01*
G01X1057698Y215361D02*
Y226660D01*
G01X1057649Y227172D02*
Y218510D01*
G01X1057255Y227565D02*
Y218510D01*
G01X1055729Y224022D02*
Y225991D01*
G01Y219691D02*
Y221660D01*
G01X1055139Y224022D02*
Y219495D01*
G01Y228747D02*
Y226778D01*
G01X1054942Y226975D02*
Y228943D01*
G01Y219298D02*
Y223825D01*
G01X1054115Y220873D02*
Y230125D01*
G01Y219888D02*
Y219101D01*
G01X1053721D02*
Y218117D01*
G01Y220873D02*
Y219888D01*
G01X1053564Y226778D02*
Y224022D01*
G01X1053406Y219888D02*
Y220873D01*
G01Y218117D02*
Y219101D01*
G01Y229810D02*
Y224810D01*
G01X1053367Y230715D02*
Y222841D01*
G01X1052580D02*
Y230715D01*
G01X1052540Y221857D02*
Y218117D01*
G01Y229810D02*
Y222054D01*
G01X1052225Y218117D02*
Y222172D01*
G01X1052580Y226778D02*
X1052807Y226384D01*
G01Y222447D02*
X1052580Y222841D01*
G01X1051399Y218117D02*
Y230125D01*
G01X1109715Y227172D02*
X1110109Y227565D01*
G01X1105778Y227172D02*
X1106172Y227565D01*
G01X1101841Y227172D02*
X1102235Y227565D01*
G01X1097904Y227172D02*
X1098298Y227565D01*
G01X1109351Y224691D02*
X1109367Y224748D01*
X1109380Y224801D01*
X1109389Y224851D01*
G01X1105414Y224691D02*
X1105430Y224748D01*
X1105443Y224801D01*
X1105452Y224851D01*
G01X1109194Y224691D02*
X1109178Y224635D01*
X1109165Y224582D01*
X1109156Y224532D01*
G01X1105257Y224691D02*
X1105241Y224635D01*
X1105228Y224582D01*
X1105219Y224532D01*
G01X1109715Y227172D02*
Y218510D01*
G01X1109666Y215361D02*
Y226660D01*
G01X1109649Y224192D02*
Y225191D01*
G01X1109469Y221266D02*
Y220085D01*
G01Y225597D02*
Y224416D01*
G01X1109389Y224851D02*
Y224532D01*
G01X1109156D02*
Y224851D01*
G01X1109076Y224416D02*
Y225597D01*
G01Y220085D02*
Y221266D01*
G01X1108896Y225191D02*
Y224192D01*
G01X1108879Y215361D02*
Y226660D01*
G01X1108830Y227172D02*
Y218510D01*
G01X1109389Y224532D02*
X1109380Y224582D01*
X1109367Y224635D01*
X1109351Y224691D01*
G01X1109156Y224851D02*
X1109165Y224801D01*
X1109178Y224748D01*
X1109194Y224691D01*
G01X1105452Y224532D02*
X1105443Y224582D01*
X1105430Y224635D01*
X1105414Y224691D01*
G01X1093967Y227172D02*
X1094361Y227565D01*
G01X1093525Y228747D02*
X1093721Y228943D01*
G01X1090030Y227172D02*
X1090424Y227565D01*
G01X1093525Y233274D02*
X1093721Y233471D01*
G01X1101477Y224691D02*
X1101493Y224748D01*
X1101506Y224801D01*
X1101515Y224851D01*
G01X1097540Y224691D02*
X1097556Y224748D01*
X1097569Y224801D01*
X1097578Y224851D01*
G01X1101320Y224691D02*
X1101304Y224635D01*
X1101291Y224582D01*
X1101282Y224532D01*
G01X1097383Y224691D02*
X1097367Y224635D01*
X1097354Y224582D01*
X1097345Y224532D01*
G01X1108436Y227565D02*
Y218510D01*
G01X1106172Y227565D02*
Y218510D01*
G01X1105778Y227172D02*
Y218510D01*
G01X1105729Y215361D02*
Y226660D01*
G01X1105712Y224192D02*
Y225191D01*
G01X1105532Y221266D02*
Y220085D01*
G01Y225597D02*
Y224416D01*
G01X1105452Y224851D02*
Y224532D01*
G01X1105219D02*
Y224851D01*
G01X1105139Y224416D02*
Y225597D01*
G01Y220085D02*
Y221266D01*
G01X1104959Y225191D02*
Y224192D01*
G01X1104942Y215361D02*
Y226660D01*
G01X1104893Y227172D02*
Y218510D01*
G01X1104499Y227565D02*
Y218510D01*
G01X1105219Y224851D02*
X1105228Y224801D01*
X1105241Y224748D01*
X1105257Y224691D01*
G01X1101515Y224532D02*
X1101506Y224582D01*
X1101493Y224635D01*
X1101477Y224691D01*
G01X1101282Y224851D02*
X1101291Y224801D01*
X1101304Y224748D01*
X1101320Y224691D01*
G01X1086093Y227172D02*
X1086487Y227565D01*
G01X1082156Y227172D02*
X1082550Y227565D01*
G01X1093603Y224691D02*
X1093619Y224748D01*
X1093632Y224801D01*
X1093641Y224851D01*
G01X1093446Y224691D02*
X1093430Y224635D01*
X1093417Y224582D01*
X1093408Y224532D01*
G01X1102235Y227565D02*
Y218510D01*
G01X1101841Y227172D02*
Y218510D01*
G01X1101792Y215361D02*
Y226660D01*
G01X1101775Y224192D02*
Y225191D01*
G01X1101595Y221266D02*
Y220085D01*
G01Y225597D02*
Y224416D01*
G01X1101515Y224851D02*
Y224532D01*
G01X1101282D02*
Y224851D01*
G01X1101202Y224416D02*
Y225597D01*
G01Y220085D02*
Y221266D01*
G01X1101022Y225191D02*
Y224192D01*
G01X1101005Y215361D02*
Y226660D01*
G01X1100956Y227172D02*
Y218510D01*
G01X1100562Y227565D02*
Y218510D01*
G01X1098298Y227565D02*
Y218510D01*
G01X1097904Y227172D02*
Y218510D01*
G01X1097855Y215361D02*
Y226660D01*
G01X1097838Y224192D02*
Y225191D01*
G01X1097658Y221266D02*
Y220085D01*
G01Y225597D02*
Y224416D01*
G01X1097578Y224851D02*
Y224532D01*
G01X1097345D02*
Y224851D01*
G01X1097265Y224416D02*
Y225597D01*
G01Y220085D02*
Y221266D01*
G01X1097085Y225191D02*
Y224192D01*
G01X1097068Y215361D02*
Y226660D01*
G01X1097019Y227172D02*
Y218510D01*
G01X1096625Y227565D02*
Y218510D01*
G01X1096084Y218117D02*
Y217329D01*
G01X1097578Y224532D02*
X1097569Y224582D01*
X1097556Y224635D01*
X1097540Y224691D01*
G01X1097345Y224851D02*
X1097354Y224801D01*
X1097367Y224748D01*
X1097383Y224691D01*
G01X1093641Y224532D02*
X1093632Y224582D01*
X1093619Y224635D01*
X1093603Y224691D01*
G01X1093408Y224851D02*
X1093417Y224801D01*
X1093430Y224748D01*
X1093446Y224691D01*
G01X1108436Y227565D02*
X1108830Y227172D01*
G01X1104499Y227565D02*
X1104893Y227172D01*
G01X1100562Y227565D02*
X1100956Y227172D01*
G01X1087619Y234928D02*
X1083682D01*
G01X1082698Y233668D02*
X1088603D01*
G01X1078219Y227172D02*
X1078613Y227565D01*
G01X1089666Y224691D02*
X1089682Y224748D01*
X1089695Y224801D01*
X1089704Y224851D01*
G01X1085729Y224691D02*
X1085745Y224748D01*
X1085758Y224801D01*
X1085767Y224851D01*
G01X1089509Y224691D02*
X1089493Y224635D01*
X1089480Y224582D01*
X1089471Y224532D01*
G01X1085572Y224691D02*
X1085556Y224635D01*
X1085543Y224582D01*
X1085534Y224532D01*
G01X1095493Y230125D02*
Y234849D01*
G01X1094902Y217723D02*
Y218117D01*
G01X1094361Y227565D02*
Y218510D01*
G01X1093967Y227172D02*
Y218510D01*
G01X1093918Y215361D02*
Y226660D01*
G01X1093901Y224192D02*
Y225191D01*
G01X1093721Y221266D02*
Y220085D01*
G01Y225597D02*
Y224416D01*
G01Y233471D02*
Y228943D01*
G01X1093641Y224851D02*
Y224532D01*
G01X1093525Y228747D02*
Y233274D01*
G01X1093408Y224532D02*
Y224851D01*
G01X1093328Y224416D02*
Y225597D01*
G01Y220085D02*
Y221266D01*
G01X1093148Y225191D02*
Y224192D01*
G01X1093131Y215361D02*
Y226660D01*
G01X1093082Y227172D02*
Y218510D01*
G01X1092688Y227565D02*
Y218510D01*
G01X1092147Y218117D02*
Y217723D01*
G01X1090965D02*
Y218117D01*
G01X1090424Y227565D02*
Y218510D01*
G01X1090030Y227172D02*
Y218510D01*
G01X1089981Y215361D02*
Y226660D01*
G01X1089964Y224192D02*
Y225191D01*
G01X1089784Y221266D02*
Y220085D01*
G01Y225597D02*
Y224416D01*
G01X1089704Y224532D02*
X1089695Y224582D01*
X1089682Y224635D01*
X1089666Y224691D01*
G01X1089471Y224851D02*
X1089480Y224801D01*
X1089493Y224748D01*
X1089509Y224691D01*
G01X1093525Y230439D02*
X1093721Y230125D01*
G01X1096625Y227565D02*
X1097019Y227172D01*
G01X1092688Y227565D02*
X1093082Y227172D01*
G01X1108896Y225191D02*
X1109028Y225163D01*
G01X1104959Y225191D02*
X1105091Y225163D01*
G01X1109649Y224192D02*
X1109517Y224220D01*
G01X1101022Y225191D02*
X1101154Y225163D01*
G01X1105712Y224192D02*
X1105580Y224220D01*
G01X1097085Y225191D02*
X1097217Y225163D01*
G01X1101775Y224192D02*
X1101643Y224220D01*
G01X1119902Y230125D02*
X1093721D01*
G01Y228943D02*
X1116359D01*
G01X1082550Y227565D02*
X1080877D01*
G01X1086487D02*
X1084814D01*
G01X1090424D02*
X1088751D01*
G01X1094361D02*
X1092688D01*
G01X1098298D02*
X1096625D01*
G01X1102235D02*
X1100562D01*
G01X1106172D02*
X1104499D01*
G01X1110109D02*
X1108436D01*
G01X1108830Y227172D02*
X1109715D01*
G01X1104893D02*
X1105778D01*
G01X1100956D02*
X1101841D01*
G01X1097019D02*
X1097904D01*
G01X1093082D02*
X1093967D01*
G01X1089145D02*
X1090030D01*
G01X1085208D02*
X1086093D01*
G01X1081271D02*
X1082156D01*
G01X1108879Y226660D02*
X1109666D01*
G01X1104942D02*
X1105729D01*
G01X1101005D02*
X1101792D01*
G01X1097068D02*
X1097855D01*
G01X1093131D02*
X1093918D01*
G01X1089194D02*
X1089981D01*
G01X1085257D02*
X1086044D01*
G01X1081320D02*
X1082107D01*
G01Y226211D02*
X1081320D01*
G01X1086044D02*
X1085257D01*
G01X1089981D02*
X1089194D01*
G01X1093918D02*
X1093131D01*
G01X1097855D02*
X1097068D01*
G01X1101792D02*
X1101005D01*
G01X1105729D02*
X1104942D01*
G01X1109666D02*
X1108879D01*
G01X1082107Y226139D02*
X1081320D01*
G01X1086044D02*
X1085257D01*
G01X1089981D02*
X1089194D01*
G01X1093918D02*
X1093131D01*
G01X1097855D02*
X1097068D01*
G01X1101792D02*
X1101005D01*
G01X1105729D02*
X1104942D01*
G01X1109666D02*
X1108879D01*
G01X1109715Y225991D02*
X1112767D01*
G01X1105778D02*
X1108830D01*
G01X1101841D02*
X1104893D01*
G01X1097904D02*
X1100956D01*
G01X1093967D02*
X1097019D01*
G01X1090030D02*
X1093082D01*
G01X1086093D02*
X1089145D01*
G01X1082156D02*
X1085208D01*
G01X1078219D02*
X1081271D01*
G01X1082156Y225873D02*
X1081271D01*
G01X1086093D02*
X1085208D01*
G01X1090030D02*
X1089145D01*
G01X1093967D02*
X1093082D01*
G01X1097904D02*
X1097019D01*
G01X1101841D02*
X1100956D01*
G01X1105778D02*
X1104893D01*
G01X1109715D02*
X1108830D01*
G01X1108879Y225676D02*
X1109666D01*
G01X1104942D02*
X1105729D01*
G01X1101005D02*
X1101792D01*
G01X1097068D02*
X1097855D01*
G01X1093131D02*
X1093918D01*
G01X1089194D02*
X1089981D01*
G01X1085257D02*
X1086044D01*
G01X1081320D02*
X1082107D01*
G01X1109076Y225597D02*
X1109469D01*
G01X1105139D02*
X1105532D01*
G01X1101202D02*
X1101595D01*
G01X1097265D02*
X1097658D01*
G01X1093328D02*
X1093721D01*
G01X1089391D02*
X1089784D01*
G01X1085454D02*
X1085847D01*
G01X1081517D02*
X1081910D01*
G01X1082156Y225479D02*
X1081271D01*
G01X1086093D02*
X1085208D01*
G01X1090030D02*
X1089145D01*
G01X1093967D02*
X1093082D01*
G01X1097904D02*
X1097019D01*
G01X1101841D02*
X1100956D01*
G01X1105778D02*
X1104893D01*
G01X1109715D02*
X1108830D01*
G01X1109028Y225163D02*
X1109517D01*
G01X1105091D02*
X1105580D01*
G01X1101154D02*
X1101643D01*
G01X1097217D02*
X1097706D01*
G01X1093280D02*
X1093769D01*
G01X1089343D02*
X1089832D01*
G01X1085406D02*
X1085895D01*
G01X1081469D02*
X1081958D01*
G01X1078021D02*
X1078152Y225191D01*
G01X1081958Y225163D02*
X1082089Y225191D01*
G01X1085895Y225163D02*
X1086026Y225191D01*
G01X1081469Y224220D02*
X1081337Y224192D01*
G01X1089832Y225163D02*
X1089964Y225191D01*
G01X1085406Y224220D02*
X1085274Y224192D01*
G01X1093769Y225163D02*
X1093901Y225191D01*
G01X1089343Y224220D02*
X1089211Y224192D01*
G01X1097706Y225163D02*
X1097838Y225191D01*
G01X1093280Y224220D02*
X1093148Y224192D01*
G01X1101643Y225163D02*
X1101775Y225191D01*
G01X1097217Y224220D02*
X1097085Y224192D01*
G01X1105580Y225163D02*
X1105712Y225191D01*
G01X1101154Y224220D02*
X1101022Y224192D01*
G01X1081792Y224691D02*
X1081808Y224748D01*
X1081821Y224801D01*
X1081830Y224851D01*
G01X1081635Y224691D02*
X1081619Y224635D01*
X1081606Y224582D01*
X1081597Y224532D01*
G01X1089704Y224851D02*
Y224532D01*
G01X1089471D02*
Y224851D01*
G01X1089391Y224416D02*
Y225597D01*
G01Y220085D02*
Y221266D01*
G01X1089211Y225191D02*
Y224192D01*
G01X1089194Y215361D02*
Y226660D01*
G01X1089145Y227172D02*
Y218510D01*
G01X1088751Y227565D02*
Y218510D01*
G01X1088603Y234849D02*
Y233274D01*
G01X1088210Y218117D02*
Y217723D01*
G01X1087619Y234849D02*
Y234928D01*
G01X1087422Y233274D02*
Y234849D01*
G01X1087107D02*
Y234928D01*
G01X1087028Y217723D02*
Y218117D01*
G01X1086487Y227565D02*
Y218510D01*
G01X1086093Y227172D02*
Y218510D01*
G01X1086044Y215361D02*
Y226660D01*
G01X1086026Y224192D02*
Y225191D01*
G01X1085847Y221266D02*
Y220085D01*
G01Y225597D02*
Y224416D01*
G01X1085767Y224851D02*
Y224532D01*
G01X1085534D02*
Y224851D01*
G01X1085454Y224416D02*
Y225597D01*
G01Y220085D02*
Y221266D01*
G01X1085274Y225191D02*
Y224192D01*
G01X1085257Y215361D02*
Y226660D01*
G01X1085208Y227172D02*
Y218510D01*
G01X1084814Y227565D02*
Y218510D01*
G01X1084273Y218117D02*
Y217723D01*
G01X1084194Y234849D02*
Y234928D01*
G01X1083879Y234849D02*
Y233274D01*
G01X1083682Y234849D02*
Y234928D01*
G01X1085767Y224532D02*
X1085758Y224582D01*
X1085745Y224635D01*
X1085729Y224691D01*
G01X1085534Y224851D02*
X1085543Y224801D01*
X1085556Y224748D01*
X1085572Y224691D01*
G01X1081830Y224532D02*
X1081821Y224582D01*
X1081808Y224635D01*
X1081792Y224691D01*
G01X1081597Y224851D02*
X1081606Y224801D01*
X1081619Y224748D01*
X1081635Y224691D01*
G01X1088751Y227565D02*
X1089145Y227172D01*
G01X1084814Y227565D02*
X1085208Y227172D01*
G01X1093148Y225191D02*
X1093280Y225163D01*
G01X1097838Y224192D02*
X1097706Y224220D01*
G01X1089211Y225191D02*
X1089343Y225163D01*
G01X1093901Y224192D02*
X1093769Y224220D01*
G01X1085274Y225191D02*
X1085406Y225163D01*
G01X1089964Y224192D02*
X1089832Y224220D01*
G01X1081337Y225191D02*
X1081469Y225163D01*
G01X1086026Y224192D02*
X1085895Y224220D01*
G01X1082089Y224192D02*
X1081958Y224220D01*
G01X1078152Y224192D02*
X1078021Y224220D01*
G01X1081910Y224416D02*
X1081517D01*
G01X1085847D02*
X1085454D01*
G01X1089784D02*
X1089391D01*
G01X1093721D02*
X1093328D01*
G01X1097658D02*
X1097265D01*
G01X1101595D02*
X1101202D01*
G01X1105532D02*
X1105139D01*
G01X1109469D02*
X1109076D01*
G01X1081958Y224220D02*
X1081469D01*
G01X1085895D02*
X1085406D01*
G01X1089832D02*
X1089343D01*
G01X1093769D02*
X1093280D01*
G01X1097706D02*
X1097217D01*
G01X1101643D02*
X1101154D01*
G01X1105580D02*
X1105091D01*
G01X1109517D02*
X1109028D01*
G01X1081271Y224022D02*
X1078219D01*
G01X1085208D02*
X1082156D01*
G01X1089145D02*
X1086093D01*
G01X1093082D02*
X1090030D01*
G01X1097019D02*
X1093967D01*
G01X1100956D02*
X1097904D01*
G01X1104893D02*
X1101841D01*
G01X1108830D02*
X1105778D01*
G01X1112767D02*
X1109715D01*
G01X1082107Y223904D02*
X1081320D01*
G01X1086044D02*
X1085257D01*
G01X1089981D02*
X1089194D01*
G01X1093918D02*
X1093131D01*
G01X1097855D02*
X1097068D01*
G01X1101792D02*
X1101005D01*
G01X1105729D02*
X1104942D01*
G01X1109666D02*
X1108879D01*
G01Y223874D02*
X1109666D01*
G01X1104942D02*
X1105729D01*
G01X1101005D02*
X1101792D01*
G01X1097068D02*
X1097855D01*
G01X1093131D02*
X1093918D01*
G01X1089194D02*
X1089981D01*
G01X1085257D02*
X1086044D01*
G01X1081320D02*
X1082107D01*
G01X1108879Y223802D02*
X1109666D01*
G01X1104942D02*
X1105729D01*
G01X1101005D02*
X1101792D01*
G01X1097068D02*
X1097855D01*
G01X1093131D02*
X1093918D01*
G01X1089194D02*
X1089981D01*
G01X1085257D02*
X1086044D01*
G01X1081320D02*
X1082107D01*
G01X1082156Y223747D02*
X1081271D01*
G01X1086093D02*
X1085208D01*
G01X1090030D02*
X1089145D01*
G01X1093967D02*
X1093082D01*
G01X1097904D02*
X1097019D01*
G01X1101841D02*
X1100956D01*
G01X1105778D02*
X1104893D01*
G01X1109715D02*
X1108830D01*
G01X1082107Y223707D02*
X1081320D01*
G01X1086044D02*
X1085257D01*
G01X1089981D02*
X1089194D01*
G01X1093918D02*
X1093131D01*
G01X1097855D02*
X1097068D01*
G01X1101792D02*
X1101005D01*
G01X1105729D02*
X1104942D01*
G01X1109666D02*
X1108879D01*
G01X1104893Y223353D02*
X1105778D01*
G01X1097019D02*
X1097904D01*
G01X1089145D02*
X1090030D01*
G01X1081271D02*
X1082156D01*
G01X1086093D02*
X1085208D01*
G01X1093967D02*
X1093082D01*
G01X1101841D02*
X1100956D01*
G01X1109715D02*
X1108830D01*
G01X1082156Y222014D02*
X1081271D01*
G01X1086093D02*
X1085208D01*
G01X1090030D02*
X1089145D01*
G01X1093967D02*
X1093082D01*
G01X1097904D02*
X1097019D01*
G01X1101841D02*
X1100956D01*
G01X1105778D02*
X1104893D01*
G01X1109715D02*
X1108830D01*
G01X1082107Y221880D02*
X1081320D01*
G01X1086044D02*
X1085257D01*
G01X1089981D02*
X1089194D01*
G01X1093918D02*
X1093131D01*
G01X1097855D02*
X1097068D01*
G01X1101792D02*
X1101005D01*
G01X1105729D02*
X1104942D01*
G01X1109666D02*
X1108879D01*
G01X1082107Y221808D02*
X1081320D01*
G01X1086044D02*
X1085257D01*
G01X1089981D02*
X1089194D01*
G01X1093918D02*
X1093131D01*
G01X1097855D02*
X1097068D01*
G01X1101792D02*
X1101005D01*
G01X1105729D02*
X1104942D01*
G01X1109666D02*
X1108879D01*
G01X1109715Y221660D02*
X1112767D01*
G01X1108879D02*
X1109666D01*
G01X1105778D02*
X1108830D01*
G01X1104942D02*
X1105729D01*
G01X1101841D02*
X1104893D01*
G01X1101005D02*
X1101792D01*
G01X1097904D02*
X1100956D01*
G01X1097068D02*
X1097855D01*
G01X1093967D02*
X1097019D01*
G01X1093131D02*
X1093918D01*
G01X1090030D02*
X1093082D01*
G01X1089194D02*
X1089981D01*
G01X1086093D02*
X1089145D01*
G01X1085257D02*
X1086044D01*
G01X1082156D02*
X1085208D01*
G01X1081320D02*
X1082107D01*
G01X1078219D02*
X1081271D01*
G01X1082156Y221621D02*
X1081271D01*
G01X1086093D02*
X1085208D01*
G01X1090030D02*
X1089145D01*
G01X1093967D02*
X1093082D01*
G01X1097904D02*
X1097019D01*
G01X1101841D02*
X1100956D01*
G01X1105778D02*
X1104893D01*
G01X1109715D02*
X1108830D01*
G01X1082107Y221463D02*
X1081320D01*
G01X1086044D02*
X1085257D01*
G01X1089981D02*
X1089194D01*
G01X1093918D02*
X1093131D01*
G01X1097855D02*
X1097068D01*
G01X1101792D02*
X1101005D01*
G01X1105729D02*
X1104942D01*
G01X1109666D02*
X1108879D01*
G01X1109076Y221266D02*
X1109469D01*
G01X1105139D02*
X1105532D01*
G01X1101202D02*
X1101595D01*
G01X1097265D02*
X1097658D01*
G01X1093328D02*
X1093721D01*
G01X1089391D02*
X1089784D01*
G01X1085454D02*
X1085847D01*
G01X1081517D02*
X1081910D01*
G01X1108879Y221092D02*
X1109666D01*
G01X1104942D02*
X1105729D01*
G01X1101005D02*
X1101792D01*
G01X1097068D02*
X1097855D01*
G01X1093131D02*
X1093918D01*
G01X1089194D02*
X1089981D01*
G01X1085257D02*
X1086044D01*
G01X1081320D02*
X1082107D01*
G01X1081910Y220085D02*
X1081517D01*
G01X1085847D02*
X1085454D01*
G01X1089784D02*
X1089391D01*
G01X1093721D02*
X1093328D01*
G01X1097658D02*
X1097265D01*
G01X1101595D02*
X1101202D01*
G01X1105532D02*
X1105139D01*
G01X1109469D02*
X1109076D01*
G01X1108879Y219722D02*
X1109666D01*
G01X1104942D02*
X1105729D01*
G01X1101005D02*
X1101792D01*
G01X1097068D02*
X1097855D01*
G01X1093131D02*
X1093918D01*
G01X1089194D02*
X1089981D01*
G01X1085257D02*
X1086044D01*
G01X1081320D02*
X1082107D01*
G01X1081271Y219691D02*
X1078219D01*
G01X1085208D02*
X1082156D01*
G01X1089145D02*
X1086093D01*
G01X1093082D02*
X1090030D01*
G01X1097019D02*
X1093967D01*
G01X1100956D02*
X1097904D01*
G01X1104893D02*
X1101841D01*
G01X1108830D02*
X1105778D01*
G01X1112767D02*
X1109715D01*
G01X1108879Y219543D02*
X1109666D01*
G01X1104942D02*
X1105729D01*
G01X1101005D02*
X1101792D01*
G01X1097068D02*
X1097855D01*
G01X1093131D02*
X1093918D01*
G01X1089194D02*
X1089981D01*
G01X1085257D02*
X1086044D01*
G01X1081320D02*
X1082107D01*
G01X1108879Y219471D02*
X1109666D01*
G01X1104942D02*
X1105729D01*
G01X1101005D02*
X1101792D01*
G01X1097068D02*
X1097855D01*
G01X1093131D02*
X1093918D01*
G01X1089194D02*
X1089981D01*
G01X1085257D02*
X1086044D01*
G01X1081320D02*
X1082107D01*
G01X1082156Y219101D02*
X1081271D01*
G01X1086093D02*
X1085208D01*
G01X1090030D02*
X1089145D01*
G01X1093967D02*
X1093082D01*
G01X1097904D02*
X1097019D01*
G01X1101841D02*
X1100956D01*
G01X1105778D02*
X1104893D01*
G01X1109715D02*
X1108830D01*
G01X1108879Y218588D02*
X1109666D01*
G01X1104942D02*
X1105729D01*
G01X1101005D02*
X1101792D01*
G01X1097068D02*
X1097855D01*
G01X1093131D02*
X1093918D01*
G01X1089194D02*
X1089981D01*
G01X1085257D02*
X1086044D01*
G01X1081320D02*
X1082107D01*
G01X1109517Y225163D02*
X1109649Y225191D01*
G01X1105091Y224220D02*
X1104959Y224192D01*
G01X1109028Y224220D02*
X1108896Y224192D01*
G01X1083091Y217723D02*
Y218117D01*
G01X1082698Y234849D02*
Y233274D01*
G01X1082550Y227565D02*
Y218510D01*
G01X1082156Y227172D02*
Y218510D01*
G01X1082107Y215361D02*
Y226660D01*
G01X1082089Y224192D02*
Y225191D01*
G01X1081910Y221266D02*
Y220085D01*
G01Y225597D02*
Y224416D01*
G01X1081830Y224851D02*
Y224532D01*
G01X1081597D02*
Y224851D01*
G01X1081517Y224416D02*
Y225597D01*
G01Y220085D02*
Y221266D01*
G01X1081337Y225191D02*
Y224192D01*
G01X1081320Y215361D02*
Y226660D01*
G01X1081271Y227172D02*
Y218510D01*
G01X1080877Y227565D02*
Y218510D01*
G01X1080336Y218117D02*
Y217723D01*
G01X1079154D02*
Y218117D01*
G01X1078613Y227565D02*
Y218510D01*
G01X1078219Y227172D02*
Y218510D01*
G01X1078170Y215361D02*
Y226660D01*
G01X1078152Y224192D02*
Y225191D01*
G01X1080877Y227565D02*
X1081271Y227172D01*
G01X1083091Y218117D02*
X1080336D01*
G01X1087028D02*
X1084273D01*
G01X1090965D02*
X1088210D01*
G01X1094902D02*
X1092147D01*
G01X1119902D02*
X1096084D01*
G01X1080336Y217723D02*
X1079154D01*
G01X1084273D02*
X1083091D01*
G01X1088210D02*
X1087028D01*
G01X1092147D02*
X1090965D01*
G01X1096084D02*
X1094902D01*
G01X1108879Y217386D02*
X1109666D01*
G01X1104942D02*
X1105729D01*
G01X1101005D02*
X1101792D01*
G01X1097068D02*
X1097855D01*
G01X1093131D02*
X1093918D01*
G01X1089194D02*
X1089981D01*
G01X1085257D02*
X1086044D01*
G01X1081320D02*
X1082107D01*
G01Y215951D02*
X1081320D01*
G01X1086044D02*
X1085257D01*
G01X1089981D02*
X1089194D01*
G01X1093918D02*
X1093131D01*
G01X1097855D02*
X1097068D01*
G01X1101792D02*
X1101005D01*
G01X1105729D02*
X1104942D01*
G01X1109666D02*
X1108879D01*
G01X1082107Y215361D02*
X1081320D01*
G01X1086044D02*
X1085257D01*
G01X1089981D02*
X1089194D01*
G01X1093918D02*
X1093131D01*
G01X1097855D02*
X1097068D01*
G01X1101792D02*
X1101005D01*
G01X1105729D02*
X1104942D01*
G01X1109666D02*
X1108879D01*
G01X1027646Y198217D02*
X1028368Y197243D01*
G01X1030533Y227369D02*
Y205471D01*
G01X1033387Y239065D02*
X1056664Y302372D01*
G01X1037062Y222841D02*
X1036652D01*
G01D02*
Y220160D01*
G01D02*
X1037062D01*
G01D02*
Y220412D01*
G01D02*
X1037226Y220244D01*
G01D02*
X1037472Y220160D01*
G01D02*
X1037800D01*
G01D02*
X1038046Y220244D01*
G01D02*
X1038292Y220495D01*
G01D02*
X1038539Y220244D01*
G01D02*
X1038785Y220160D01*
G01D02*
X1039113D01*
G01D02*
X1039359Y220244D01*
G01D02*
X1039523Y220412D01*
G01D02*
X1039687Y220830D01*
G01D02*
Y222841D01*
G01D02*
X1039277D01*
G01D02*
Y220830D01*
G01D02*
X1039194Y220663D01*
G01D02*
X1039113Y220579D01*
G01D02*
X1038948Y220495D01*
G01D02*
X1038702D01*
G01D02*
X1038539Y220579D01*
G01D02*
X1038456Y220663D01*
G01D02*
X1038374Y220830D01*
G01D02*
Y222841D01*
G01D02*
X1037964D01*
G01D02*
Y220830D01*
G01D02*
X1037882Y220663D01*
G01D02*
X1037800Y220579D01*
G01D02*
X1037636Y220495D01*
G01D02*
X1037472D01*
G01D02*
X1037226Y220579D01*
G01D02*
X1037062Y220747D01*
G01D02*
Y222841D01*
G01X1033371D02*
X1032961D01*
G01D02*
Y220160D01*
G01D02*
X1033371D01*
G01D02*
Y220412D01*
G01D02*
X1033535Y220244D01*
G01D02*
X1033781Y220160D01*
G01D02*
X1034109D01*
G01D02*
X1034355Y220244D01*
G01D02*
X1034602Y220495D01*
G01D02*
X1034848Y220244D01*
G01D02*
X1035094Y220160D01*
G01D02*
X1035422D01*
G01D02*
X1035668Y220244D01*
G01D02*
X1035832Y220412D01*
G01D02*
X1035996Y220830D01*
G01D02*
Y222841D01*
G01D02*
X1035586D01*
G01D02*
Y220830D01*
G01D02*
X1035503Y220663D01*
G01D02*
X1035422Y220579D01*
G01D02*
X1035257Y220495D01*
G01D02*
X1035011D01*
G01D02*
X1034848Y220579D01*
G01D02*
X1034765Y220663D01*
G01D02*
X1034683Y220830D01*
G01D02*
Y222841D01*
G01D02*
X1034273D01*
G01D02*
Y220830D01*
G01D02*
X1034191Y220663D01*
G01D02*
X1034109Y220579D01*
G01D02*
X1033945Y220495D01*
G01D02*
X1033781D01*
G01D02*
X1033535Y220579D01*
G01D02*
X1033371Y220747D01*
G01D02*
Y222841D01*
G01X1029762Y220579D02*
Y221166D01*
G01D02*
X1029844Y221668D01*
G01D02*
X1030172Y222171D01*
G01D02*
X1030418Y222338D01*
G01D02*
X1030828Y222422D01*
G01D02*
X1031239Y222338D01*
G01D02*
X1031485Y222171D01*
G01D02*
X1031813Y221668D01*
G01D02*
X1031895Y221166D01*
G01D02*
Y220579D01*
G01D02*
X1031813Y220077D01*
G01D02*
X1031485Y219574D01*
G01D02*
X1031239Y219406D01*
G01D02*
X1030828Y219323D01*
G01D02*
X1030418Y219406D01*
G01D02*
X1030172Y219574D01*
G01D02*
X1029844Y220077D01*
G01D02*
X1029762Y220579D01*
G01X1029434Y220077D02*
X1029352Y220495D01*
G01X1029516Y219825D02*
X1029434Y220077D01*
G01X1029680Y219490D02*
X1029516Y219825D01*
G01X1029926Y219239D02*
X1029680Y219490D01*
G01X1030336Y218988D02*
X1029926Y219239D01*
G01X1030828Y218904D02*
X1030336Y218988D01*
G01X1031320D02*
X1030828Y218904D01*
G01X1031731Y219239D02*
X1031320Y218988D01*
G01X1031977Y219490D02*
X1031731Y219239D01*
G01X1032141Y219825D02*
X1031977Y219490D01*
G01X1032223Y220077D02*
X1032141Y219825D01*
G01X1032305Y220495D02*
X1032223Y220077D01*
G01X1032305Y221249D02*
Y220495D01*
G01X1032223Y221668D02*
X1032305Y221249D01*
G01X1032141Y221919D02*
X1032223Y221668D01*
G01X1031977Y222255D02*
X1032141Y221919D01*
G01X1031731Y222506D02*
X1031977Y222255D01*
G01X1031320Y222757D02*
X1031731Y222506D01*
G01X1030828Y222841D02*
X1031320Y222757D01*
G01X1030336D02*
X1030828Y222841D01*
G01X1029926Y222506D02*
X1030336Y222757D01*
G01X1029680Y222255D02*
X1029926Y222506D01*
G01X1029516Y221919D02*
X1029680Y222255D01*
G01X1029434Y221668D02*
X1029516Y221919D01*
G01X1029352Y221249D02*
X1029434Y221668D01*
G01X1029352Y220495D02*
Y221249D01*
G01X1027383Y221166D02*
X1028696D01*
G01D02*
Y221501D01*
G01D02*
X1027383D01*
G01D02*
Y221166D01*
G01Y220160D02*
X1028696D01*
G01D02*
Y220495D01*
G01D02*
X1027383D01*
G01D02*
Y220160D01*
G01X1082728Y265951D02*
Y260620D01*
G01X1083574Y265951D02*
X1082728D01*
G01X1083574Y259180D02*
Y265951D01*
G01X1082305Y259180D02*
X1083574D01*
G01X1080189Y265231D02*
X1082305Y259180D01*
G01X1078072D02*
X1080189Y265231D01*
G01X1076803Y259180D02*
X1078072D01*
G01X1076803Y265951D02*
Y259180D01*
G01X1077649Y265951D02*
X1076803D01*
G01X1077649Y260620D02*
Y265951D01*
G01X1079624D02*
X1077649Y260620D01*
G01X1080753Y265951D02*
X1079624D01*
G01X1082728Y260620D02*
X1080753Y265951D01*
G01X1074828D02*
Y260620D01*
G01X1075674Y265951D02*
X1074828D01*
G01X1075674Y259180D02*
Y265951D01*
G01X1074405Y259180D02*
X1075674D01*
G01X1072289Y265231D02*
X1074405Y259180D01*
G01X1070172D02*
X1072289Y265231D01*
G01X1068903Y259180D02*
X1070172D01*
G01X1068903Y265951D02*
Y259180D01*
G01X1069749Y265951D02*
X1068903D01*
G01X1069749Y260620D02*
Y265951D01*
G01X1071724D02*
X1069749Y260620D01*
G01X1072853Y265951D02*
X1071724D01*
G01X1074828Y260620D02*
X1072853Y265951D01*
G01X1062695D02*
Y265231D01*
G01X1067774Y265951D02*
X1062695D01*
G01X1067774Y265231D02*
Y265951D01*
G01X1063824Y265231D02*
X1067774D01*
G01X1067351Y262061D02*
X1063824Y265231D01*
G01X1067633Y261629D02*
X1067351Y262061D01*
G01X1067774Y261053D02*
X1067633Y261629D01*
G01X1067774Y260764D02*
Y261053D01*
G01X1067633Y260188D02*
X1067774Y260764D01*
G01X1067068Y259612D02*
X1067633Y260188D01*
G01X1066504Y259323D02*
X1067068Y259612D01*
G01X1065658Y259180D02*
X1066504Y259323D01*
G01X1065094Y259180D02*
X1065658D01*
G01X1064106Y259323D02*
X1065094Y259180D01*
G01X1063542Y259612D02*
X1064106Y259323D01*
G01X1062978Y260188D02*
X1063542Y259612D01*
G01X1062836Y260764D02*
X1062978Y260188D01*
G01X1063542Y260764D02*
X1062836D01*
G01X1063824Y260332D02*
X1063542Y260764D01*
G01X1064247Y260044D02*
X1063824Y260332D01*
G01X1064952Y259900D02*
X1064247Y260044D01*
G01X1065517Y259900D02*
X1064952D01*
G01X1066222Y260044D02*
X1065517Y259900D01*
G01X1066645Y260332D02*
X1066222Y260044D01*
G01X1066928Y260764D02*
X1066645Y260332D01*
G01X1066928Y261053D02*
Y260764D01*
G01X1066645Y261629D02*
X1066928Y261053D01*
G01X1062695Y265231D02*
X1066645Y261629D01*
G01X1059592Y262493D02*
X1061566Y263502D01*
G01Y261485D02*
X1059592Y262493D01*
G01X1061285Y261053D02*
X1061566Y261485D01*
G01X1058604Y262493D02*
X1061285Y261053D01*
G01Y263934D02*
X1058604Y262493D01*
G01X1061566Y263502D02*
X1061285Y263934D01*
G01X1052679Y262781D02*
Y265951D01*
G01X1056629Y262781D02*
X1052679D01*
G01X1056629Y265951D02*
Y262781D01*
G01X1057476Y265951D02*
X1056629D01*
G01X1057476Y259180D02*
Y265951D01*
G01X1056629Y259180D02*
X1057476D01*
G01X1056629Y261917D02*
Y259180D01*
G01X1052679Y261917D02*
X1056629D01*
G01X1052679Y259180D02*
Y261917D01*
G01X1051832Y259180D02*
X1052679D01*
G01X1051832Y265951D02*
Y259180D01*
G01X1052679Y265951D02*
X1051832D01*
G01X1104549Y262408D02*
X1106911Y260046D01*
G01D02*
Y264377D01*
G01Y260046D02*
Y264377D01*
G01X1108486Y265361D02*
Y264377D01*
G01X1110946Y265361D02*
X1108486D01*
G01X1106911Y264377D02*
X1108486D01*
G01X1104549Y266739D02*
X1106911Y264377D01*
G01X1109962Y263392D02*
X1106616D01*
G01D02*
Y247644D01*
G01D02*
X1109962D01*
G01X1106616D02*
X1149923D01*
G01X1106616Y263392D02*
Y247644D01*
G01X1149923Y263392D02*
X1106616D01*
G01X1103368Y267920D02*
X1153171D01*
G01X1103368Y243117D02*
Y267920D01*
G01Y243117D02*
X1121773D01*
G01X1141360D02*
X1103368D01*
G01X1104549Y252566D02*
X1103368D01*
G01X1104549Y244298D02*
Y252566D01*
G01X1151990Y244298D02*
X1104549D01*
G01X1106911Y254928D02*
X1103368D01*
G01X1104549Y252566D02*
X1106911Y254928D01*
G01X1104549Y244298D02*
X1106911Y246660D01*
G01D02*
Y254928D01*
G01Y246660D02*
Y254928D01*
G01X1108486Y246660D02*
X1106911D01*
G01X1108486D02*
Y245676D01*
G01D02*
X1110946D01*
G01X1108486Y246660D02*
X1106911D01*
G01X1108486Y245676D02*
X1110946D01*
G01X1108486Y246660D02*
Y245676D01*
G01X1103368Y254928D02*
X1106911D01*
G01X1103368Y260046D02*
Y254928D01*
G01X1106911Y260046D02*
X1103368D01*
G01X1108486Y264377D02*
X1106911D01*
G01X1108486Y265361D02*
Y264377D01*
G01X1110946Y265361D02*
X1108486D01*
G01X1103368Y260046D02*
X1106911D01*
G01X1103368Y252566D02*
Y254928D01*
G01Y243117D02*
Y252566D01*
G01Y262408D02*
Y267920D01*
G01Y260046D02*
Y262408D01*
G01X1104549Y266739D02*
X1151990D01*
G01X1104549Y262408D02*
Y266739D01*
G01X1103368Y262408D02*
X1104549D01*
G01X1153171Y267920D02*
X1103368D01*
G01X1046158Y229337D02*
X1040177D01*
G01X1032502Y221662D02*
G03X1040177Y229337I-1969J9644D01*
G01X1032502Y221662D02*
Y215681D01*
G01X1028565D02*
Y221662D01*
G01Y240949D02*
Y246930D01*
G01X1032502D02*
Y240949D01*
G01X1040177Y233274D02*
G03X1032502Y240949I-9644J-1969D01*
G01X1040177Y233274D02*
X1046158D01*
G01X1028565Y215681D02*
G03X1032502I1968J15625D01*
G01X1046158Y229337D02*
G03X1046281Y231306I-15625J1964D01*
G01X1032502Y246930D02*
G03X1028565I-1969J-15624D01*
G01X1046281Y231306D02*
G03X1046158Y233274I-15748J4D01*
G01X1032502Y221662D02*
G03X1040177Y229337I-1969J9644D01*
G01X1046158D02*
X1040177D01*
G01X1032502Y215681D02*
G03X1046158Y229337I-1969J15625D01*
G01X1032502Y221662D02*
Y215681D01*
G01X1028565D02*
Y221662D01*
G01Y240949D02*
Y246930D01*
G01X1046158Y233274D02*
G03X1032502Y246930I-15625J-1969D01*
G01X1040177Y233274D02*
X1046158D01*
G01X1040177D02*
G03X1032502Y240949I-9644J-1969D01*
G01Y246930D02*
Y240949D01*
G01X1040630Y224908D02*
G03X1042598I984J0D01*
G01D02*
G03X1040630I-984J0D01*
G01X1035946Y220225D02*
G03X1037915I985J0D01*
G01D02*
G03X1035946I-984J0D01*
G01X1040630Y237703D02*
G03X1042598I984J0D01*
G01D02*
G03X1040630I-984J0D01*
G01X1035946Y242386D02*
G03X1037915I985J0D01*
G01D02*
G03X1035946I-984J0D01*
G01X1040630Y224908D02*
G03X1042598I984J0D01*
G01D02*
G03X1040630I-984J0D01*
G01X1035946Y220225D02*
G03X1037915I985J0D01*
G01D02*
G03X1035946I-984J0D01*
G01X1040630Y237703D02*
G03X1042598I984J0D01*
G01D02*
G03X1040630I-984J0D01*
G01X1035946Y242386D02*
G03X1037915I985J0D01*
G01D02*
G03X1035946I-984J0D01*
G01X1040630Y224908D02*
G03X1042598I984J0D01*
G01D02*
G03X1040630I-984J0D01*
G01X1035946Y220225D02*
G03X1037915I985J0D01*
G01D02*
G03X1035946I-984J0D01*
G01X1040630Y237703D02*
G03X1042598I984J0D01*
G01D02*
G03X1040630I-984J0D01*
G01X1035946Y242386D02*
G03X1037915I985J0D01*
G01D02*
G03X1035946I-984J0D01*
G01X1040630Y224908D02*
G03X1042598I984J0D01*
G01D02*
G03X1040630I-984J0D01*
G01X1035946Y220225D02*
G03X1037915I985J0D01*
G01D02*
G03X1035946I-984J0D01*
G01X1040630Y237703D02*
G03X1042598I984J0D01*
G01D02*
G03X1040630I-984J0D01*
G01X1035946Y242386D02*
G03X1037915I985J0D01*
G01D02*
G03X1035946I-984J0D01*
G01X1081985Y304538D02*
X1085882D01*
G01X1082472Y306703D02*
X1081985Y304538D01*
G01X1083446Y308147D02*
X1082472Y306703D01*
G01X1084421Y308868D02*
X1083446Y308147D01*
G01X1085395Y309590D02*
X1084421Y308868D01*
G01X1085882Y310312D02*
X1085395Y309590D01*
G01X1085882Y311755D02*
Y310312D01*
G01X1085395Y312477D02*
X1085882Y311755D01*
G01X1084421Y313199D02*
X1085395Y312477D01*
G01X1083446Y313199D02*
X1084421D01*
G01X1082472Y312477D02*
X1083446Y313199D01*
G01X1081985Y311755D02*
X1082472Y312477D01*
G01X1096348Y306703D02*
X1095627Y308868D01*
G01X1097792Y305259D02*
X1096348Y306703D01*
G01X1099957Y304538D02*
X1097792Y305259D01*
G01X1102122D02*
X1099957Y304538D01*
G01X1103566Y306703D02*
X1102122Y305259D01*
G01X1104288Y308868D02*
X1103566Y306703D01*
G01Y311034D02*
X1104288Y308868D01*
G01X1102122Y312477D02*
X1103566Y311034D01*
G01X1099957Y313199D02*
X1102122Y312477D01*
G01X1097792D02*
X1099957Y313199D01*
G01X1096348Y311034D02*
X1097792Y312477D01*
G01X1095627Y308868D02*
X1096348Y311034D01*
G01X1109124Y306703D02*
X1113509D01*
G01X1112534Y313199D02*
X1109124Y306703D01*
G01X1071374Y302372D02*
X1178199D01*
G01X1056664D02*
X1071374D01*
G01X1096348D02*
X1103566Y315364D01*
G01X1089780Y304538D02*
X1093678Y313199D01*
G01X1089780D02*
X1093678Y304538D01*
G01X1066055Y382084D02*
X1067030Y381363D01*
G01X1065081D02*
X1066055Y382084D01*
G01X1064107Y379919D02*
X1065081Y381363D01*
G01X1064107Y378476D02*
Y379919D01*
G01X1065081Y377032D02*
X1064107Y378476D01*
G01X1066055Y376310D02*
X1065081Y377032D01*
G01X1067030D02*
X1066055Y376310D01*
G01X1075800Y379919D02*
Y378476D01*
G01X1074825Y381363D02*
X1075800Y379919D01*
G01X1073851Y382084D02*
X1074825Y381363D01*
G01X1072876D02*
X1073851Y382084D01*
G01X1071902Y379919D02*
X1072876Y381363D01*
G01X1071902Y378476D02*
Y379919D01*
G01X1072876Y377032D02*
X1071902Y378476D01*
G01X1073851Y376310D02*
X1072876Y377032D01*
G01X1074825D02*
X1073851Y376310D01*
G01X1075800Y378476D02*
X1074825Y377032D01*
G01X1081646Y380641D02*
Y376310D01*
G01X1080672Y382084D02*
X1081646Y380641D01*
G01X1079697Y382084D02*
X1080672D01*
G01X1078723Y380641D02*
X1079697Y382084D01*
G01X1084569Y380641D02*
Y376310D01*
G01X1083595Y382084D02*
X1084569Y380641D01*
G01X1082620Y382084D02*
X1083595D01*
G01X1081646Y380641D02*
X1082620Y382084D01*
G01X1088467Y376310D02*
X1087492Y378476D01*
G01X1089441Y376310D02*
X1088467D01*
G01X1090416Y377032D02*
X1089441Y376310D01*
G01X1091390Y378476D02*
X1090416Y377032D01*
G01X1091390Y379919D02*
Y378476D01*
G01X1090416Y381363D02*
X1091390Y379919D01*
G01X1089441Y382084D02*
X1090416Y381363D01*
G01X1088467D02*
X1089441Y382084D01*
G01X1087492Y379919D02*
X1088467Y381363D01*
G01X1099185Y379919D02*
Y378476D01*
G01X1098211Y381363D02*
X1099185Y379919D01*
G01X1097237Y382084D02*
X1098211Y381363D01*
G01X1096262D02*
X1097237Y382084D01*
G01X1095288Y379919D02*
X1096262Y381363D01*
G01X1095288Y378476D02*
Y379919D01*
G01X1096262Y377032D02*
X1095288Y378476D01*
G01X1097237Y376310D02*
X1096262Y377032D01*
G01X1098211D02*
X1097237Y376310D01*
G01X1099185Y378476D02*
X1098211Y377032D01*
G01X1106493Y380641D02*
Y376310D01*
G01X1105519Y382084D02*
X1106493Y380641D01*
G01X1104544Y382084D02*
X1105519D01*
G01X1103570Y380641D02*
X1104544Y382084D01*
G01X1028758Y426730D02*
X1032656D01*
G01X1028758Y435391D02*
Y426730D01*
G01X1036553Y435391D02*
X1040451D01*
G01X1036553Y426730D02*
Y435391D01*
G01X1040451Y426730D02*
X1036553D01*
G01X1069196Y427451D02*
X1069683Y426730D01*
G01X1069196D02*
Y427451D01*
G01X1069683Y426730D02*
X1069196D01*
G01X1078453Y427451D02*
X1077479Y426730D01*
G01X1078940Y428173D02*
X1078453Y427451D01*
G01X1079428Y429617D02*
X1078940Y428173D01*
G01X1079428Y432504D02*
Y429617D01*
G01X1078940Y433947D02*
X1079428Y432504D01*
G01X1078453Y434669D02*
X1078940Y433947D01*
G01X1077479Y435391D02*
X1078453Y434669D01*
G01X1076504D02*
X1077479Y435391D01*
G01X1076017Y433947D02*
X1076504Y434669D01*
G01X1075530Y432504D02*
X1076017Y433947D01*
G01X1075530Y429617D02*
Y432504D01*
G01X1076017Y428173D02*
X1075530Y429617D01*
G01X1076504Y427451D02*
X1076017Y428173D01*
G01X1077479Y426730D02*
X1076504Y427451D01*
G01X1086248D02*
X1085274Y426730D01*
G01X1086735Y428173D02*
X1086248Y427451D01*
G01X1087223Y429617D02*
X1086735Y428173D01*
G01X1087223Y432504D02*
Y429617D01*
G01X1086735Y433947D02*
X1087223Y432504D01*
G01X1086248Y434669D02*
X1086735Y433947D01*
G01X1085274Y435391D02*
X1086248Y434669D01*
G01X1084300D02*
X1085274Y435391D01*
G01X1083812Y433947D02*
X1084300Y434669D01*
G01X1083325Y432504D02*
X1083812Y433947D01*
G01X1083325Y429617D02*
Y432504D01*
G01X1083812Y428173D02*
X1083325Y429617D01*
G01X1084300Y427451D02*
X1083812Y428173D01*
G01X1085274Y426730D02*
X1084300Y427451D01*
G01X1094044D02*
X1093069Y426730D01*
G01X1094531Y428173D02*
X1094044Y427451D01*
G01X1095018Y429617D02*
X1094531Y428173D01*
G01X1095018Y432504D02*
Y429617D01*
G01X1094531Y433947D02*
X1095018Y432504D01*
G01X1094044Y434669D02*
X1094531Y433947D01*
G01X1093069Y435391D02*
X1094044Y434669D01*
G01X1092095D02*
X1093069Y435391D01*
G01X1091607Y433947D02*
X1092095Y434669D01*
G01X1091120Y432504D02*
X1091607Y433947D01*
G01X1091120Y429617D02*
Y432504D01*
G01X1091607Y428173D02*
X1091120Y429617D01*
G01X1092095Y427451D02*
X1091607Y428173D01*
G01X1093069Y426730D02*
X1092095Y427451D01*
G01X1061888Y435391D02*
Y426730D01*
G01X1036553Y431060D02*
X1038989D01*
G01X1103570Y376310D02*
Y382084D01*
G01X1087492D02*
Y373423D01*
G01X1078723Y382084D02*
Y376310D01*
G01X1037675Y499879D02*
G03X1031297Y493501I0J-6378D01*
G01Y491533D02*
G03X1037675Y485155I6378J0D01*
G01X1031297Y491533D02*
Y493501D01*
G01X1065392Y492517D02*
G03I-591J0D01*
G01X1062223Y493304D02*
G03X1061632Y493895I-591J0D01*
G01X1062223Y492911D02*
G03X1061435Y493698I-788J-1D01*
G01X1063207Y492911D02*
G03X1062419Y493698I-787J0D01*
G01X1065786Y492517D02*
G03I-985J0D01*
G01X1063207Y493304D02*
G03X1061632Y494879I-1575J0D01*
G01X1066455Y493698D02*
G03X1062597Y497556I-3858J0D01*
G01X1067045Y493698D02*
G03X1062597Y498147I-4449J0D01*
G01X1067636Y493698D02*
G03X1062597Y498737I-5039J0D01*
G01X1068778Y493501D02*
G03X1062400Y499879I-6378J0D01*
G01X1061632Y491139D02*
G03X1062223Y491729I0J591D01*
G01X1061435Y491336D02*
G03X1062223Y492123I1J787D01*
G01X1062419Y491336D02*
G03X1063207Y492123I1J787D01*
G01X1061632Y490155D02*
G03X1063207Y491729I0J1575D01*
G01X1062597Y487477D02*
G03X1066455Y491336I0J3858D01*
G01X1062597Y486887D02*
G03X1067045Y491336I-1J4449D01*
G01X1062597Y486296D02*
G03X1067636Y491336I0J5039D01*
G01X1062400Y485155D02*
G03X1068778Y491533I0J6378D01*
G01X1038640Y493698D02*
G03X1037853Y492911I0J-787D01*
G01Y492123D02*
G03X1038640Y491336I787J0D01*
G01X1035864Y492517D02*
G03I-590J0D01*
G01X1038443Y493895D02*
G03X1037853Y493304I1J-591D01*
G01Y491729D02*
G03X1038443Y491139I590J0D01*
G01X1037656Y493698D02*
G03X1036868Y492911I0J-788D01*
G01Y492123D02*
G03X1037656Y491336I787J0D01*
G01X1036258Y492517D02*
G03I-984J0D01*
G01X1038443Y494879D02*
G03X1036868Y493304I0J-1575D01*
G01Y491729D02*
G03X1038443Y490155I1575J1D01*
G01X1037478Y497556D02*
G03X1033620Y493698I0J-3858D01*
G01Y491336D02*
G03X1037478Y487477I3859J0D01*
G01Y498147D02*
G03X1033030Y493698I1J-4449D01*
G01Y491336D02*
G03X1037478Y486887I4449J0D01*
G01Y498737D02*
G03X1032439Y493698I0J-5039D01*
G01Y491336D02*
G03X1037478Y486296I5040J0D01*
G01X1055746Y501572D02*
X1044329D01*
G01X1043738Y501474D02*
X1037675D01*
G01X1062400D02*
X1056337D01*
G01X1044329Y500536D02*
X1055746D01*
G01X1043738Y500489D02*
X1037675D01*
G01X1062400D02*
X1056337D01*
G01X1043738Y500411D02*
X1037675D01*
G01X1062400D02*
X1056337D01*
G01X1055746Y500391D02*
X1044329D01*
G01X1055746Y500132D02*
X1044329D01*
G01X1062400Y499879D02*
X1037675D01*
G01X1062597Y498737D02*
X1037478D01*
G01Y498147D02*
X1062597D01*
G01Y497556D02*
X1037478D01*
G01X1060471Y497162D02*
X1061258D01*
G01X1058502D02*
X1059290D01*
G01X1056534D02*
X1057321D01*
G01X1054565D02*
X1055353D01*
G01X1052597D02*
X1053384D01*
G01X1050628D02*
X1051415D01*
G01X1048660D02*
X1049447D01*
G01X1046691D02*
X1047478D01*
G01X1044723D02*
X1045510D01*
G01X1042754D02*
X1043541D01*
G01X1040786D02*
X1041573D01*
G01X1038817D02*
X1039604D01*
G01X1038063Y496300D02*
X1037910D01*
G01X1037656Y493698D02*
X1037514Y493683D01*
X1037377Y493638D01*
X1037251Y493566D01*
X1037139Y493467D01*
X1037048Y493349D01*
X1036981Y493213D01*
X1036939Y493066D01*
X1036925Y492911D01*
G01X1037656Y493698D02*
X1037481Y493678D01*
X1037314Y493620D01*
X1037165Y493526D01*
X1037040Y493401D01*
X1036946Y493252D01*
X1036888Y493085D01*
X1036868Y492911D01*
G01X1061650Y493698D02*
X1061792Y493683D01*
X1061929Y493638D01*
X1062055Y493566D01*
X1062167Y493467D01*
X1062258Y493349D01*
X1062325Y493213D01*
X1062367Y493066D01*
X1062381Y492911D01*
G01X1060471Y495273D02*
X1061258D01*
G01X1058502D02*
X1059290D01*
G01X1056534D02*
X1057321D01*
G01X1054565D02*
X1055353D01*
G01X1052597D02*
X1053384D01*
G01X1050628D02*
X1051415D01*
G01X1048660D02*
X1049447D01*
G01X1046691D02*
X1047478D01*
G01X1044723D02*
X1045510D01*
G01X1042754D02*
X1043541D01*
G01X1040786D02*
X1041573D01*
G01X1038817D02*
X1039604D01*
G01X1037910Y495080D02*
X1038063D01*
G01X1038443Y494879D02*
X1061632D01*
G01X1039604Y494407D02*
X1038817D01*
G01X1041573D02*
X1040786D01*
G01X1043541D02*
X1042754D01*
G01X1045510D02*
X1044723D01*
G01X1047478D02*
X1046691D01*
G01X1049447D02*
X1048660D01*
G01X1051415D02*
X1050628D01*
G01X1053384D02*
X1052597D01*
G01X1055353D02*
X1054565D01*
G01X1057321D02*
X1056534D01*
G01X1059290D02*
X1058502D01*
G01X1061258D02*
X1060471D01*
G01X1061632Y493895D02*
X1038443D01*
G01X1067045Y493698D02*
X1066455D01*
G01X1033620D02*
X1033030D01*
G01X1062419D02*
X1037656D01*
G01X1037853Y493304D02*
X1036868D01*
G01X1063207D02*
X1062223D01*
G01X1063207Y492911D02*
X1036868D01*
G01X1062144Y492753D02*
X1037931D01*
G01X1062144Y492281D02*
X1037931D01*
G01X1036868Y492123D02*
X1063207D01*
G01X1062223Y491729D02*
X1063207D01*
G01X1036868D02*
X1037853D01*
G01X1033030Y491336D02*
X1033620D01*
G01X1066455D02*
X1067045D01*
G01X1062419D02*
X1037656D01*
G01X1038443Y491139D02*
X1061632D01*
G01X1039604Y490627D02*
X1038817D01*
G01X1041573D02*
X1040786D01*
G01X1043541D02*
X1042754D01*
G01X1045510D02*
X1044723D01*
G01X1047478D02*
X1046691D01*
G01X1049447D02*
X1048660D01*
G01X1051415D02*
X1050628D01*
G01X1053384D02*
X1052597D01*
G01X1055353D02*
X1054565D01*
G01X1057321D02*
X1056534D01*
G01X1059290D02*
X1058502D01*
G01X1061258D02*
X1060471D01*
G01X1061632Y490155D02*
X1038443D01*
G01X1062419Y491336D02*
X1062562Y491351D01*
X1062698Y491395D01*
X1062824Y491467D01*
X1062936Y491566D01*
X1063027Y491685D01*
X1063095Y491820D01*
X1063136Y491968D01*
X1063151Y492123D01*
G01X1062419Y491336D02*
X1062595Y491355D01*
X1062761Y491414D01*
X1062910Y491507D01*
X1063035Y491632D01*
X1063129Y491782D01*
X1063187Y491948D01*
X1063207Y492123D01*
G01X1062419Y493698D02*
X1062623Y493671D01*
X1062813Y493592D01*
X1062976Y493467D01*
X1063102Y493304D01*
X1063180Y493114D01*
X1063207Y492911D01*
G01X1037656Y491336D02*
X1037481Y491355D01*
X1037314Y491414D01*
X1037165Y491507D01*
X1037040Y491632D01*
X1036946Y491782D01*
X1036888Y491948D01*
X1036868Y492123D01*
G01X1038425Y491336D02*
X1038283Y491351D01*
X1038147Y491395D01*
X1038021Y491467D01*
X1037908Y491566D01*
X1037817Y491685D01*
X1037750Y491820D01*
X1037708Y491968D01*
X1037694Y492123D01*
G01X1060471Y489761D02*
X1061258D01*
G01X1058502D02*
X1059290D01*
G01X1056534D02*
X1057321D01*
G01X1054565D02*
X1055353D01*
G01X1052597D02*
X1053384D01*
G01X1050628D02*
X1051415D01*
G01X1048660D02*
X1049447D01*
G01X1046691D02*
X1047478D01*
G01X1044723D02*
X1045510D01*
G01X1042754D02*
X1043541D01*
G01X1040786D02*
X1041573D01*
G01X1038817D02*
X1039604D01*
G01X1060471Y487871D02*
X1061258D01*
G01X1058502D02*
X1059290D01*
G01X1056534D02*
X1057321D01*
G01X1054565D02*
X1055353D01*
G01X1052597D02*
X1053384D01*
G01X1050628D02*
X1051415D01*
G01X1048660D02*
X1049447D01*
G01X1046691D02*
X1047478D01*
G01X1044723D02*
X1045510D01*
G01X1042754D02*
X1043541D01*
G01X1040786D02*
X1041573D01*
G01X1038817D02*
X1039604D01*
G01X1062597Y487477D02*
X1037478D01*
G01X1062597Y486887D02*
X1037478D01*
G01X1062597Y486296D02*
X1037478D01*
G01X1037675Y485155D02*
X1062400D01*
G01X1044329Y484902D02*
X1055746D01*
G01X1044329Y484643D02*
X1055746D01*
G01X1043738Y484623D02*
X1037675D01*
G01X1062400D02*
X1056337D01*
G01Y484544D02*
X1062400D01*
G01X1037675D02*
X1043738D01*
G01X1055746Y484498D02*
X1044329D01*
G01X1043738Y483560D02*
X1037675D01*
G01X1062400D02*
X1056337D01*
G01X1055746Y483462D02*
X1044329D01*
G01X1068778Y493501D02*
Y491533D01*
G01X1067636Y493698D02*
Y491336D01*
G01X1067045Y493698D02*
Y491336D01*
G01X1037910Y495288D02*
X1037758Y495469D01*
G01Y495262D02*
X1037910Y495080D01*
G01X1062381Y492123D02*
X1062367Y491970D01*
X1062326Y491823D01*
X1062259Y491687D01*
X1062167Y491566D01*
X1062057Y491469D01*
X1061931Y491396D01*
X1061795Y491351D01*
X1061650Y491336D01*
G01X1066455D02*
Y493698D01*
G01X1063207Y493304D02*
Y491729D01*
G01X1063151Y492123D02*
Y492911D01*
G01X1062597Y487477D02*
Y486887D01*
G01Y498147D02*
Y497556D01*
G01X1062538Y499877D02*
Y485156D01*
G01X1062400Y499879D02*
Y501474D01*
G01Y483560D02*
Y485155D01*
G01X1062381Y492123D02*
Y492911D01*
G01X1062223Y493304D02*
Y491729D01*
G01X1062144Y492753D02*
Y492281D01*
G01X1061650Y491336D02*
Y493698D01*
G01X1061632Y491139D02*
Y490155D01*
G01Y494879D02*
Y493895D01*
G01X1061612Y500489D02*
Y501474D01*
G01Y483560D02*
Y484544D01*
G01X1061553Y492281D02*
Y492753D01*
G01X1061258Y490627D02*
Y487871D01*
G01Y497162D02*
Y494407D01*
G01X1061061Y500489D02*
Y501474D01*
G01Y484544D02*
Y483560D01*
G01X1060471Y490627D02*
Y487871D01*
G01Y497162D02*
Y494407D01*
G01X1063151Y492911D02*
X1063137Y493063D01*
X1063095Y493211D01*
X1063028Y493346D01*
X1062936Y493467D01*
X1062826Y493565D01*
X1062701Y493637D01*
X1062564Y493682D01*
X1062419Y493698D01*
G01X1060274Y500489D02*
Y501474D01*
G01Y484544D02*
Y483560D01*
G01X1060175Y500489D02*
Y501474D01*
G01Y484544D02*
Y483560D01*
G01X1060077Y500489D02*
Y501474D01*
G01Y483560D02*
Y484544D01*
G01X1059290Y490627D02*
Y487871D01*
G01Y497162D02*
Y494407D01*
G01X1058896Y500489D02*
Y501474D01*
G01Y483560D02*
Y484544D01*
G01X1058797Y500489D02*
Y501474D01*
G01Y484544D02*
Y483560D01*
G01X1058699Y500489D02*
Y501474D01*
G01Y484544D02*
Y483560D01*
G01X1058502Y490627D02*
Y487871D01*
G01Y497162D02*
Y494407D01*
G01X1057912Y500489D02*
Y501474D01*
G01Y484544D02*
Y483560D01*
G01X1057321Y490627D02*
Y487871D01*
G01Y497162D02*
Y494407D01*
G01X1057124Y484544D02*
Y483560D01*
G01Y501474D02*
Y500489D01*
G01X1056534Y490627D02*
Y487871D01*
G01Y497162D02*
Y494407D01*
G01X1056337Y485155D02*
Y483560D01*
G01Y501474D02*
Y499879D01*
G01X1055746D02*
Y501572D01*
G01Y483462D02*
Y485155D01*
G01X1055353Y490627D02*
Y487871D01*
G01Y497162D02*
Y494407D01*
G01X1055156Y500391D02*
Y501572D01*
G01Y483462D02*
Y484643D01*
G01X1054565Y490627D02*
Y487871D01*
G01Y497162D02*
Y494407D01*
G01X1054368Y500391D02*
Y501572D01*
G01Y483462D02*
Y484643D01*
G01X1053778Y500391D02*
Y501572D01*
G01Y483462D02*
Y484643D01*
G01X1053384Y490627D02*
Y487871D01*
G01Y497162D02*
Y494407D01*
G01X1053187Y500391D02*
Y501572D01*
G01Y483462D02*
Y484643D01*
G01X1052597Y490627D02*
Y487871D01*
G01Y497162D02*
Y494407D01*
G01X1051612Y500391D02*
Y501572D01*
G01Y483462D02*
Y484643D01*
G01X1051415Y490627D02*
Y487871D01*
G01Y497162D02*
Y494407D01*
G01X1051022Y500391D02*
Y501572D01*
G01Y483462D02*
Y484643D01*
G01X1050628Y490627D02*
Y487871D01*
G01Y497162D02*
Y494407D01*
G01X1050431Y484643D02*
Y483462D01*
G01Y501572D02*
Y500391D01*
G01X1049644D02*
Y501572D01*
G01Y483462D02*
Y484643D01*
G01X1049447Y490627D02*
Y487871D01*
G01Y497162D02*
Y494407D01*
G01X1049053Y500391D02*
Y501572D01*
G01Y483462D02*
Y484643D01*
G01X1048660Y490627D02*
Y487871D01*
G01Y497162D02*
Y494407D01*
G01X1048463Y500391D02*
Y501572D01*
G01Y483462D02*
Y484643D01*
G01X1047478Y490627D02*
Y487871D01*
G01Y497162D02*
Y494407D01*
G01X1046888Y500391D02*
Y501572D01*
G01Y483462D02*
Y484643D01*
G01X1046691Y490627D02*
Y487871D01*
G01Y497162D02*
Y494407D01*
G01X1046297Y500391D02*
Y501572D01*
G01Y483462D02*
Y484643D01*
G01X1045707D02*
Y483462D01*
G01Y501572D02*
Y500391D01*
G01X1045510Y490627D02*
Y487871D01*
G01Y497162D02*
Y494407D01*
G01X1044919Y484643D02*
Y483462D01*
G01Y501572D02*
Y500391D01*
G01X1044723Y490627D02*
Y487871D01*
G01Y497162D02*
Y494407D01*
G01X1044329Y485155D02*
Y483462D01*
G01Y501572D02*
Y499879D01*
G01X1043738Y483560D02*
Y485155D01*
G01Y501474D02*
Y499879D01*
G01X1043541Y490627D02*
Y487871D01*
G01Y497162D02*
Y494407D01*
G01X1042951Y483560D02*
Y484544D01*
G01Y501474D02*
Y500489D01*
G01X1042754Y490627D02*
Y487871D01*
G01Y497162D02*
Y494407D01*
G01X1042164Y483560D02*
Y484544D01*
G01Y501474D02*
Y500489D01*
G01X1041573Y490627D02*
Y487871D01*
G01Y497162D02*
Y494407D01*
G01X1037694Y492911D02*
X1037708Y493063D01*
X1037749Y493211D01*
X1037816Y493346D01*
X1037908Y493467D01*
X1038018Y493565D01*
X1038144Y493637D01*
X1038280Y493682D01*
X1038425Y493698D01*
G01X1041376Y483560D02*
Y484544D01*
G01Y501474D02*
Y500489D01*
G01X1041278Y483560D02*
Y484544D01*
G01Y501474D02*
Y500489D01*
G01X1041179D02*
Y501474D01*
G01Y483560D02*
Y484544D01*
G01X1040786Y490627D02*
Y487871D01*
G01Y497162D02*
Y494407D01*
G01X1039998Y500489D02*
Y501474D01*
G01Y483560D02*
Y484544D01*
G01X1039900Y483560D02*
Y484544D01*
G01Y501474D02*
Y500489D01*
G01X1039801Y483560D02*
Y484544D01*
G01Y501474D02*
Y500489D01*
G01X1039604Y490627D02*
Y487871D01*
G01Y497162D02*
Y494407D01*
G01X1039014Y483560D02*
Y484544D01*
G01Y501474D02*
Y500489D01*
G01X1038817Y490627D02*
Y487871D01*
G01Y497162D02*
Y494407D01*
G01X1038522Y492281D02*
Y492753D01*
G01X1038463Y484544D02*
Y483560D01*
G01Y501474D02*
Y500489D01*
G01X1038443Y493895D02*
Y494879D01*
G01Y491139D02*
Y490155D01*
G01X1038425Y491336D02*
Y493698D01*
G01X1038063Y495080D02*
Y496300D01*
G01X1037931Y492753D02*
Y492281D01*
G01X1037910Y496300D02*
Y495288D01*
G01X1037853Y491729D02*
Y493304D01*
G01X1037758Y495469D02*
Y495262D01*
G01X1037694Y492123D02*
Y492911D01*
G01X1037675Y485155D02*
Y483560D01*
G01Y501474D02*
Y499879D01*
G01X1037538Y499877D02*
Y485156D01*
G01X1037478Y487477D02*
Y486887D01*
G01Y498147D02*
Y497556D01*
G01X1036925Y492123D02*
Y492911D01*
G01X1036868Y491729D02*
Y493304D01*
G01X1036925Y492123D02*
X1036939Y491970D01*
X1036980Y491823D01*
X1037047Y491687D01*
X1037139Y491566D01*
X1037249Y491469D01*
X1037375Y491396D01*
X1037511Y491351D01*
X1037656Y491336D01*
G01X1033620D02*
Y493698D01*
G01X1033030Y491336D02*
Y493698D01*
G01X1032439Y491336D02*
Y493698D01*
G01X1099552Y490465D02*
X1102124Y489151D01*
G01X1104697Y494781D02*
X1105799D01*
G01X1095694D02*
X1096796D01*
G01X1089447D02*
X1090549D01*
G01X1110760Y492716D02*
X1109841D01*
G01X1090549Y491216D02*
X1095694D01*
G01Y490090D02*
X1090549D01*
G01X1101757Y492341D02*
X1102124Y491778D01*
G01X1101757Y488588D02*
X1098266Y490465D01*
G01X1107269Y486900D02*
X1108187D01*
G01X1090549Y485962D02*
X1089447D01*
G01X1096796D02*
X1095694D01*
G01X1105799D02*
X1104697D01*
G01X1108187D02*
X1107269D01*
G01X1116271D02*
X1109657D01*
G01X1109841Y492716D02*
X1110025Y493467D01*
G01X1109657Y485962D02*
Y486900D01*
G01X1108187D02*
Y485962D01*
G01X1107269D02*
Y486900D01*
G01X1105799Y494781D02*
Y485962D01*
G01X1104697D02*
Y493279D01*
G01X1109657Y486900D02*
X1114801Y491591D01*
G01X1103594Y491966D02*
Y493467D01*
G01X1104697Y493279D02*
X1103594Y491966D01*
G01X1102124Y489151D02*
X1101757Y488588D01*
G01X1096796Y494781D02*
Y485962D01*
G01X1095694Y491216D02*
Y494781D01*
G01Y485962D02*
Y490090D01*
G01X1102124Y491778D02*
X1099552Y490465D01*
G01X1103594Y493467D02*
X1104697Y494781D01*
G01X1090549Y490090D02*
Y485962D01*
G01Y494781D02*
Y491216D01*
G01X1089447Y485962D02*
Y494781D01*
G01X1098266Y490465D02*
X1101757Y492341D01*
G01X1096967Y450982D02*
Y451277D01*
G01D02*
X1099329D01*
G01D02*
Y450982D01*
G01D02*
X1098173D01*
G01D02*
X1099329Y449899D01*
G01D02*
Y449505D01*
G01D02*
X1098374Y450391D01*
G01D02*
X1096967Y449505D01*
G01D02*
Y449899D01*
G01D02*
X1098123Y450637D01*
G01D02*
X1097771Y450982D01*
G01D02*
X1096967D01*
G01X1097771Y460775D02*
X1099128Y460332D01*
G01X1097771Y459889D02*
Y460775D01*
G01X1099128Y460332D02*
X1097771Y459889D01*
G01X1099329Y460135D02*
X1096967Y459348D01*
G01D02*
Y459643D01*
G01D02*
X1097570Y459840D01*
G01D02*
Y460824D01*
G01D02*
X1096967Y461021D01*
G01D02*
Y461316D01*
G01D02*
X1099329Y460529D01*
G01D02*
Y460135D01*
G01X1082794Y450982D02*
Y451277D01*
G01D02*
X1085156D01*
G01D02*
Y450982D01*
G01D02*
X1084000D01*
G01D02*
X1085156Y449899D01*
G01D02*
Y449505D01*
G01D02*
X1084201Y450391D01*
G01D02*
X1082794Y449505D01*
G01D02*
Y449899D01*
G01D02*
X1083950Y450637D01*
G01D02*
X1083598Y450982D01*
G01D02*
X1082794D01*
G01X1083598Y460775D02*
X1084955Y460332D01*
G01X1083598Y459889D02*
Y460775D01*
G01X1084955Y460332D02*
X1083598Y459889D01*
G01X1085156Y460135D02*
X1082794Y459348D01*
G01D02*
Y459643D01*
G01D02*
X1083397Y459840D01*
G01D02*
Y460824D01*
G01D02*
X1082794Y461021D01*
G01D02*
Y461316D01*
G01D02*
X1085156Y460529D01*
G01D02*
Y460135D01*
G01X1068620Y450982D02*
Y451277D01*
G01D02*
X1070983D01*
G01D02*
Y450982D01*
G01D02*
X1069827D01*
G01D02*
X1070983Y449899D01*
G01D02*
Y449505D01*
G01D02*
X1070028Y450391D01*
G01D02*
X1068620Y449505D01*
G01D02*
Y449899D01*
G01D02*
X1069776Y450637D01*
G01D02*
X1069424Y450982D01*
G01D02*
X1068620D01*
G01X1069424Y460775D02*
X1070781Y460332D01*
G01X1069424Y459889D02*
Y460775D01*
G01X1070781Y460332D02*
X1069424Y459889D01*
G01X1070983Y460135D02*
X1068620Y459348D01*
G01D02*
Y459643D01*
G01D02*
X1069224Y459840D01*
G01D02*
Y460824D01*
G01D02*
X1068620Y461021D01*
G01D02*
Y461316D01*
G01D02*
X1070983Y460529D01*
G01D02*
Y460135D01*
G01X1054447Y450982D02*
Y451277D01*
G01D02*
X1056809D01*
G01D02*
Y450982D01*
G01D02*
X1055653D01*
G01D02*
X1056809Y449899D01*
G01D02*
Y449505D01*
G01D02*
X1055854Y450391D01*
G01D02*
X1054447Y449505D01*
G01D02*
Y449899D01*
G01D02*
X1055603Y450637D01*
G01D02*
X1055251Y450982D01*
G01D02*
X1054447D01*
G01X1055251Y460775D02*
X1056608Y460332D01*
G01X1055251Y459889D02*
Y460775D01*
G01X1056608Y460332D02*
X1055251Y459889D01*
G01X1056809Y460135D02*
X1054447Y459348D01*
G01D02*
Y459643D01*
G01D02*
X1055050Y459840D01*
G01D02*
Y460824D01*
G01D02*
X1054447Y461021D01*
G01D02*
Y461316D01*
G01D02*
X1056809Y460529D01*
G01D02*
Y460135D01*
G01X1030692Y472458D02*
X1030311D01*
G01D02*
Y474951D01*
G01D02*
X1030692D01*
G01D02*
Y474717D01*
G01D02*
X1030845Y474873D01*
G01D02*
X1031074Y474951D01*
G01D02*
X1031379D01*
G01D02*
X1031607Y474873D01*
G01D02*
X1031837Y474639D01*
G01D02*
X1032065Y474873D01*
G01D02*
X1032294Y474951D01*
G01D02*
X1032599D01*
G01D02*
X1032828Y474873D01*
G01D02*
X1032981Y474717D01*
G01D02*
X1033133Y474328D01*
G01D02*
Y472458D01*
G01D02*
X1032752D01*
G01D02*
Y474328D01*
G01D02*
X1032676Y474483D01*
G01D02*
X1032599Y474561D01*
G01D02*
X1032447Y474639D01*
G01D02*
X1032218D01*
G01D02*
X1032065Y474561D01*
G01D02*
X1031989Y474483D01*
G01D02*
X1031913Y474328D01*
G01D02*
Y472458D01*
G01D02*
X1031531D01*
G01D02*
Y474328D01*
G01D02*
X1031455Y474483D01*
G01D02*
X1031379Y474561D01*
G01D02*
X1031226Y474639D01*
G01D02*
X1031074D01*
G01D02*
X1030845Y474561D01*
G01D02*
X1030692Y474405D01*
G01D02*
Y472458D01*
G01X1027260Y474951D02*
Y474717D01*
G01D02*
X1027412Y474873D01*
G01D02*
X1027641Y474951D01*
G01D02*
X1027946D01*
G01D02*
X1028175Y474873D01*
G01D02*
X1028404Y474639D01*
G01D02*
X1028633Y474873D01*
G01D02*
X1028861Y474951D01*
G01D02*
X1029166D01*
G01D02*
X1029396Y474873D01*
G01D02*
X1029548Y474717D01*
G01D02*
X1029701Y474328D01*
G01D02*
Y472458D01*
G01D02*
X1029319D01*
G01D02*
Y474328D01*
G01D02*
X1029243Y474483D01*
G01D02*
X1029166Y474561D01*
G01D02*
X1029014Y474639D01*
G01D02*
X1028785D01*
G01D02*
X1028633Y474561D01*
G01D02*
X1028556Y474483D01*
G01D02*
X1028480Y474328D01*
G01D02*
Y472458D01*
G01D02*
X1028099D01*
G01D02*
Y474328D01*
G01D02*
X1028022Y474483D01*
G01D02*
X1027946Y474561D01*
G01D02*
X1027794Y474639D01*
G01D02*
X1027641D01*
G01D02*
X1027412Y474561D01*
G01D02*
X1027260Y474405D01*
G01D02*
Y472458D01*
G01X1112321Y458201D02*
G03Y452621I0J-2790D01*
G01X1109172Y455411D02*
Y449112D01*
G01D02*
X1115471D01*
G01X1109172Y455411D02*
G03X1112321Y452261I3150J0D01*
G01X1115471Y461710D02*
X1109172D01*
G01D02*
Y455411D01*
G01X1112321Y458560D02*
G03X1109172Y455411I0J-3149D01*
G01Y449112D02*
X1115471D01*
G01X1109172Y461710D02*
Y449112D01*
G01X1115471Y461710D02*
X1109172D01*
G01X1098148Y452621D02*
G03Y458201I0J2790D01*
G01D02*
G03Y452621I0J-2790D01*
G01Y456240D02*
G03Y454582I0J-829D01*
G01D02*
G03Y456240I0J829D01*
G01X1094998Y455411D02*
Y449112D01*
G01D02*
X1101298D01*
G01D02*
Y455411D01*
G01X1098148Y452261D02*
G03X1101298Y455411I0J3150D01*
G01X1094998D02*
G03X1098148Y452261I3150J0D01*
G01X1101298Y455411D02*
G03X1098148Y458560I-3150J-1D01*
G01X1101298Y455411D02*
Y461710D01*
G01D02*
X1094998D01*
G01D02*
Y455411D01*
G01X1098148Y458560D02*
G03X1094998Y455411I0J-3150D01*
G01X1101298Y449112D02*
Y461710D01*
G01X1094998Y449112D02*
X1101298D01*
G01X1094998Y461710D02*
Y449112D01*
G01X1101298Y461710D02*
X1094998D01*
G01X1083975Y452621D02*
G03Y458201I0J2790D01*
G01D02*
G03Y452621I0J-2790D01*
G01Y456240D02*
G03Y454582I0J-829D01*
G01D02*
G03Y456240I0J829D01*
G01X1080825Y455411D02*
Y449112D01*
G01D02*
X1087124D01*
G01D02*
Y455411D01*
G01X1083975Y452261D02*
G03X1087124Y455411I-1J3150D01*
G01X1080825D02*
G03X1083975Y452261I3150J0D01*
G01X1087124Y455411D02*
G03X1083975Y458560I-3149J0D01*
G01X1087124Y455411D02*
Y461710D01*
G01D02*
X1080825D01*
G01D02*
Y455411D01*
G01X1083975Y458560D02*
G03X1080825Y455411I0J-3150D01*
G01X1087124Y449112D02*
Y461710D01*
G01X1080825Y449112D02*
X1087124D01*
G01X1080825Y461710D02*
Y449112D01*
G01X1087124Y461710D02*
X1080825D01*
G01X1069802Y452621D02*
G03Y458201I0J2790D01*
G01D02*
G03Y452621I0J-2790D01*
G01Y456240D02*
G03Y454582I0J-829D01*
G01D02*
G03Y456240I0J829D01*
G01X1066652Y455411D02*
Y449112D01*
G01D02*
X1072951D01*
G01D02*
Y455411D01*
G01X1069802Y452261D02*
G03X1072951Y455411I-1J3150D01*
G01X1066652D02*
G03X1069802Y452261I3150J0D01*
G01X1072951Y455411D02*
G03X1069802Y458560I-3149J0D01*
G01X1072951Y455411D02*
Y461710D01*
G01D02*
X1066652D01*
G01D02*
Y455411D01*
G01X1069802Y458560D02*
G03X1066652Y455411I-1J-3149D01*
G01X1072951Y449112D02*
Y461710D01*
G01X1066652Y449112D02*
X1072951D01*
G01X1066652Y461710D02*
Y449112D01*
G01X1072951Y461710D02*
X1066652D01*
G01X1055628Y452621D02*
G03Y458201I0J2790D01*
G01D02*
G03Y452621I0J-2790D01*
G01Y456240D02*
G03Y454582I0J-829D01*
G01D02*
G03Y456240I0J829D01*
G01X1052479Y455411D02*
Y449112D01*
G01D02*
X1058778D01*
G01D02*
Y455411D01*
G01X1055628Y452261D02*
G03X1058778Y455411I0J3150D01*
G01X1052479D02*
G03X1055628Y452261I3150J0D01*
G01X1058778Y455411D02*
G03X1055628Y458560I-3149J0D01*
G01X1058778Y455411D02*
Y461710D01*
G01D02*
X1052479D01*
G01D02*
Y455411D01*
G01X1055628Y458560D02*
G03X1052479Y455411I0J-3149D01*
G01X1058778Y449112D02*
Y461710D01*
G01X1052479Y449112D02*
X1058778D01*
G01X1052479Y461710D02*
Y449112D01*
G01X1058778Y461710D02*
X1052479D01*
G01X1041725Y463285D02*
X1035744D01*
G01X1028069Y455610D02*
G03X1035744Y463285I-1968J9643D01*
G01X1028069Y455610D02*
Y449629D01*
G01Y480878D02*
Y474897D01*
G01X1035744Y467222D02*
G03X1028069Y474897I-9644J-1969D01*
G01X1035744Y467222D02*
X1041725D01*
G01Y463285D02*
G03X1041849Y465253I-15624J1972D01*
G01D02*
G03X1041725Y467222I-15748J-3D01*
G01X1028069Y455610D02*
G03X1035744Y463285I-1968J9643D01*
G01X1041725D02*
X1035744D01*
G01X1028069Y449629D02*
G03X1041725Y463285I-1968J15624D01*
G01X1028069Y455610D02*
Y449629D01*
G01X1041725Y467222D02*
G03X1028069Y480878I-15624J-1968D01*
G01X1035744Y467222D02*
X1041725D01*
G01X1035744D02*
G03X1028069Y474897I-9644J-1969D01*
G01Y480878D02*
Y474897D01*
G01X1036198Y458856D02*
G03X1038166I984J0D01*
G01D02*
G03X1036198I-984J0D01*
G01X1031514Y454172D02*
G03X1033483I985J0D01*
G01D02*
G03X1031514I-984J0D01*
G01X1036198Y471651D02*
G03X1038166I984J0D01*
G01D02*
G03X1036198I-984J0D01*
G01X1031514Y476334D02*
G03X1033483I985J0D01*
G01D02*
G03X1031514I-984J0D01*
G01X1036198Y458856D02*
G03X1038166I984J0D01*
G01D02*
G03X1036198I-984J0D01*
G01X1031514Y454172D02*
G03X1033483I985J0D01*
G01D02*
G03X1031514I-984J0D01*
G01X1036198Y471651D02*
G03X1038166I984J0D01*
G01D02*
G03X1036198I-984J0D01*
G01X1031514Y476334D02*
G03X1033483I985J0D01*
G01D02*
G03X1031514I-984J0D01*
G01X1036198Y458856D02*
G03X1038166I984J0D01*
G01D02*
G03X1036198I-984J0D01*
G01X1031514Y454172D02*
G03X1033483I985J0D01*
G01D02*
G03X1031514I-984J0D01*
G01X1036198Y471651D02*
G03X1038166I984J0D01*
G01D02*
G03X1036198I-984J0D01*
G01X1031514Y476334D02*
G03X1033483I985J0D01*
G01D02*
G03X1031514I-984J0D01*
G01X1036198Y458856D02*
G03X1038166I984J0D01*
G01D02*
G03X1036198I-984J0D01*
G01X1031514Y454172D02*
G03X1033483I985J0D01*
G01D02*
G03X1031514I-984J0D01*
G01X1036198Y471651D02*
G03X1038166I984J0D01*
G01D02*
G03X1036198I-984J0D01*
G01X1031514Y476334D02*
G03X1033483I985J0D01*
G01D02*
G03X1031514I-984J0D01*
G01X1164178Y-381883D02*
Y-399206D01*
G01X1124637Y113617D02*
X1124149Y114339D01*
G01X1125124Y112895D02*
X1124637Y113617D01*
G01X1126098Y112895D02*
X1125124D01*
G01X1126585Y113617D02*
X1126098Y112895D01*
G01X1127072Y114339D02*
X1126585Y113617D01*
G01X1140227D02*
X1139253Y115060D01*
G01X1141202Y112895D02*
X1140227Y113617D01*
G01X1142176D02*
X1141202Y112895D01*
G01X1143150Y115060D02*
X1142176Y113617D01*
G01X1148022D02*
X1147048Y115060D01*
G01X1148997Y112895D02*
X1148022Y113617D01*
G01X1149971D02*
X1148997Y112895D01*
G01X1150458Y114339D02*
X1149971Y113617D01*
G01X1143150Y121556D02*
Y112895D01*
G01X1133406Y118669D02*
Y112895D01*
G01X1167935Y162454D02*
Y166839D01*
G01X1161439Y165864D02*
X1167935Y162454D01*
G01X1170100Y165864D02*
X1161439D01*
G01X1169378Y173173D02*
X1170100Y172198D01*
G01X1168657Y173660D02*
X1169378Y173173D01*
G01X1167213Y174147D02*
X1168657Y173660D01*
G01X1164326Y174147D02*
X1167213D01*
G01X1162882Y173660D02*
X1164326Y174147D01*
G01X1162161Y173173D02*
X1162882Y173660D01*
G01X1161439Y172198D02*
X1162161Y173173D01*
G01Y171224D02*
X1161439Y172198D01*
G01X1162882Y170737D02*
X1162161Y171224D01*
G01X1164326Y170249D02*
X1162882Y170737D01*
G01X1167213Y170249D02*
X1164326D01*
G01X1168657Y170737D02*
X1167213Y170249D01*
G01X1169378Y171224D02*
X1168657Y170737D01*
G01X1170100Y172198D02*
X1169378Y171224D01*
G01Y179506D02*
X1170100Y179993D01*
G01Y179506D02*
X1169378D01*
G01X1170100Y179993D02*
Y179506D01*
G01X1169378Y186327D02*
X1168657Y185840D01*
G01X1170100Y187302D02*
X1169378Y186327D01*
G01X1170100Y188276D02*
Y187302D01*
G01X1169378Y189250D02*
X1170100Y188276D01*
G01X1168657Y189738D02*
X1169378Y189250D01*
G01X1167213Y190225D02*
X1168657Y189738D01*
G01X1165769D02*
X1167213Y190225D01*
G01X1165048Y189250D02*
X1165769Y189738D01*
G01X1164326Y188276D02*
X1165048Y189250D01*
G01X1164326Y187302D02*
Y188276D01*
G01X1165048Y186327D02*
X1164326Y187302D01*
G01X1161439Y186814D02*
X1165048Y186327D01*
G01X1161439Y189738D02*
Y186814D01*
G01X1169378Y196558D02*
X1170100Y195584D01*
G01X1168657Y197046D02*
X1169378Y196558D01*
G01X1167213Y197533D02*
X1168657Y197046D01*
G01X1162882D02*
X1164326Y197533D01*
G01X1162161Y196558D02*
X1162882Y197046D01*
G01X1161439Y195584D02*
X1162161Y196558D01*
G01Y194610D02*
X1161439Y195584D01*
G01X1162882Y194123D02*
X1162161Y194610D01*
G01X1164326Y193635D02*
X1162882Y194123D01*
G01X1167213Y193635D02*
X1164326D01*
G01X1168657Y194123D02*
X1167213Y193635D01*
G01X1169378Y194610D02*
X1168657Y194123D01*
G01X1170100Y195584D02*
X1169378Y194610D01*
G01X1110508Y118669D02*
X1110995Y117948D01*
G01X1127072Y115060D02*
Y114339D01*
G01X1126585Y115782D02*
X1127072Y115060D01*
G01X1125611Y116504D02*
X1126585Y115782D01*
G01X1124637Y117226D02*
X1125611Y116504D01*
G01X1124637Y117948D02*
Y117226D01*
G01X1125124Y118669D02*
X1124637Y117948D01*
G01X1126098Y118669D02*
X1125124D01*
G01X1126585Y117948D02*
X1126098Y118669D01*
G01X1142176Y117948D02*
X1143150Y116504D01*
G01X1141202Y118669D02*
X1142176Y117948D01*
G01X1140227D02*
X1141202Y118669D01*
G01X1139253Y116504D02*
X1140227Y117948D01*
G01X1139253Y115060D02*
Y116504D01*
G01X1150458D02*
X1147048D01*
G01X1149971Y117948D02*
X1150458Y116504D01*
G01X1148997Y118669D02*
X1149971Y117948D01*
G01X1148022D02*
X1148997Y118669D01*
G01X1147048Y116504D02*
X1148022Y117948D01*
G01X1147048Y115060D02*
Y116504D01*
G01X1133406Y121556D02*
Y120835D01*
G01X1117736Y217541D02*
X1117857Y217582D01*
G01X1115807Y217171D02*
X1115687Y217130D01*
G01X1115727Y216925D02*
X1115807Y216966D01*
G01X1115687Y217130D02*
X1115566Y217048D01*
G01X1117696Y217746D02*
X1117536Y217623D01*
G01X1118761Y221857D02*
X1119076Y222172D01*
G01X1117656Y217459D02*
X1117736Y217541D01*
G01X1115647Y216843D02*
X1115727Y216925D01*
G01X1115566Y217048D02*
X1115486Y216966D01*
G01X1117536Y217623D02*
X1117415Y217459D01*
G01X1117737Y226778D02*
X1117934Y226975D01*
G01X1119076Y228747D02*
X1118761Y228432D01*
G01X1116162Y226778D02*
X1116359Y226975D01*
G01X1119076Y230125D02*
X1118761Y229810D01*
G01X1118131Y230518D02*
X1117934Y230321D01*
G01X1116162Y228747D02*
X1116359Y228943D01*
G01X1118721Y222841D02*
X1118494Y222447D01*
G01X1118721Y226778D02*
X1118494Y226384D01*
G01X1117616Y217336D02*
X1117656Y217459D01*
G01X1117415D02*
X1117375Y217336D01*
G01X1115486Y216966D02*
X1115446Y216843D01*
G01X1113652Y227172D02*
X1114046Y227565D01*
G01X1113288Y224691D02*
X1113304Y224748D01*
X1113317Y224801D01*
X1113326Y224851D01*
G01X1113131Y224691D02*
X1113115Y224635D01*
X1113102Y224582D01*
X1113093Y224532D01*
G01X1115606Y216638D02*
X1115647Y216843D01*
G01X1115446D02*
X1115405Y216638D01*
G01X1119902Y218117D02*
Y230125D01*
G01X1119076Y222172D02*
Y218117D01*
G01X1118918Y230125D02*
Y230046D01*
G01X1118862Y215858D02*
Y217787D01*
G01X1118761Y218117D02*
Y221857D01*
G01Y229810D02*
Y222054D01*
G01X1118721Y230715D02*
Y222841D01*
G01X1118621Y217582D02*
Y216966D01*
G01Y216720D02*
Y215858D01*
G01X1117934Y222841D02*
Y230715D01*
G01X1117895Y219101D02*
Y218117D01*
G01Y220873D02*
Y219888D01*
G01Y229810D02*
Y224810D01*
G01X1117737Y224022D02*
Y226778D01*
G01X1117616Y217212D02*
Y217336D01*
G01X1117580Y219888D02*
Y220873D01*
G01Y218117D02*
Y219101D01*
G01X1117375Y217336D02*
Y217171D01*
G01X1117186Y219888D02*
Y219101D01*
G01Y230125D02*
Y220873D01*
G01X1117053Y217582D02*
Y217787D01*
G01Y215858D02*
Y217171D01*
G01X1116950Y230125D02*
Y230046D01*
G01X1116852Y217787D02*
Y217582D01*
G01Y217171D02*
Y215858D01*
G01X1116531D02*
Y217171D01*
G01X1116359Y223825D02*
Y219298D01*
G01Y228943D02*
Y226975D01*
G01X1116330Y217171D02*
Y216966D01*
G01Y216802D02*
Y215858D01*
G01X1116162Y226778D02*
Y228747D01*
G01Y219495D02*
Y224022D01*
G01X1115606Y215858D02*
Y216638D01*
G01X1115572Y221660D02*
Y219691D01*
G01Y225991D02*
Y224022D01*
G01X1115405Y216638D02*
Y215858D01*
G01X1115084Y217171D02*
Y217500D01*
G01X1114843Y215858D02*
Y217459D01*
G01X1113326Y224532D02*
X1113317Y224582D01*
X1113304Y224635D01*
X1113288Y224691D01*
G01X1113093Y224851D02*
X1113102Y224801D01*
X1113115Y224748D01*
X1113131Y224691D01*
G01X1117656Y217089D02*
X1117616Y217212D01*
G01X1117375Y217171D02*
X1117415Y217048D01*
G01X1114602Y217787D02*
Y215858D01*
G01X1114046Y227565D02*
Y218510D01*
G01X1113652Y227172D02*
Y218510D01*
G01X1113603Y215361D02*
Y226660D01*
G01X1113586Y224192D02*
Y225191D01*
G01X1113406Y221266D02*
Y220085D01*
G01Y225597D02*
Y224416D01*
G01X1113326Y224851D02*
Y224532D01*
G01X1113093D02*
Y224851D01*
G01X1113013Y224416D02*
Y225597D01*
G01Y220085D02*
Y221266D01*
G01X1112833Y225191D02*
Y224192D01*
G01X1112816Y215361D02*
Y226660D01*
G01X1112767Y227172D02*
Y218510D01*
G01X1112373Y227565D02*
Y218510D01*
G01X1110109Y227565D02*
Y218510D01*
G01X1117934Y226778D02*
X1118161Y226384D01*
G01Y222447D02*
X1117934Y222841D01*
G01X1118721Y230321D02*
X1118525Y230518D01*
G01X1117895Y229810D02*
X1117580Y230125D01*
G01X1117895Y228432D02*
X1117580Y228747D01*
G01X1117415Y217048D02*
X1117536Y216884D01*
G01X1117737Y224022D02*
X1117934Y223825D01*
G01X1116359D02*
X1116162Y224022D01*
G01X1112373Y227565D02*
X1112767Y227172D01*
G01X1115084Y217500D02*
X1114843Y217787D01*
G01Y217459D02*
X1115084Y217171D01*
G01X1117736Y217007D02*
X1117656Y217089D01*
G01X1116330Y216966D02*
X1116249Y217048D01*
G01Y216884D02*
X1116330Y216802D01*
G01X1116359Y219298D02*
X1116162Y219495D01*
G01X1117536Y216884D02*
X1117696Y216761D01*
G01X1116249Y217048D02*
X1116129Y217130D01*
G01Y216966D02*
X1116249Y216884D01*
G01X1112833Y225191D02*
X1112965Y225163D01*
G01X1113586Y224192D02*
X1113454Y224220D01*
G01X1118721Y230715D02*
X1117934D01*
G01X1118525Y230518D02*
X1118131D01*
G01X1118721Y230420D02*
X1117934D01*
G01Y230321D02*
X1118721D01*
G01X1116950Y230046D02*
X1118918D01*
G01X1117186Y229810D02*
X1118761D01*
G01Y228747D02*
X1117895D01*
G01X1119902D02*
X1119076D01*
G01X1118721Y228550D02*
X1117934D01*
G01X1118761Y228432D02*
X1117895D01*
G01X1118721Y227754D02*
X1117934D01*
G01Y227574D02*
X1118721D01*
G01X1114046Y227565D02*
X1112373D01*
G01X1112767Y227172D02*
X1113652D01*
G01X1117934Y227119D02*
X1118721D01*
G01Y227021D02*
X1117934D01*
G01X1116359Y226975D02*
X1118721D01*
G01X1117737Y226778D02*
X1116162D01*
G01X1112816Y226660D02*
X1113603D01*
G01X1118494Y226384D02*
X1118161D01*
G01X1113603Y226211D02*
X1112816D01*
G01X1113603Y226139D02*
X1112816D01*
G01X1113652Y225991D02*
X1115572D01*
G01X1118761D02*
X1117186D01*
G01X1113652Y225873D02*
X1112767D01*
G01X1112816Y225676D02*
X1113603D01*
G01X1113013Y225597D02*
X1113406D01*
G01X1113652Y225479D02*
X1112767D01*
G01X1118721Y225400D02*
X1117934D01*
G01X1112965Y225163D02*
X1113454D01*
G01X1117895Y224810D02*
X1118761D01*
G01X1118721Y224793D02*
X1117934D01*
G01Y224613D02*
X1118721D01*
G01X1117857Y216966D02*
X1117736Y217007D01*
G01X1116129Y217130D02*
X1115968Y217171D01*
G01Y217007D02*
X1116129Y216966D01*
G01X1117696Y216761D02*
X1117897Y216720D01*
G01X1113406Y224416D02*
X1113013D01*
G01X1113454Y224220D02*
X1112965D01*
G01X1116162Y224022D02*
X1117737D01*
G01X1115572D02*
X1113652D01*
G01X1113603Y223904D02*
X1112816D01*
G01Y223874D02*
X1113603D01*
G01X1117934Y223825D02*
X1116359D01*
G01X1112816Y223802D02*
X1113603D01*
G01X1118721Y223773D02*
X1117934D01*
G01X1113652Y223747D02*
X1112767D01*
G01X1113603Y223707D02*
X1112816D01*
G01X1118721Y223602D02*
X1117934D01*
G01Y223589D02*
X1118721D01*
G01X1112767Y223353D02*
X1113652D01*
G01X1117934Y223243D02*
X1118721D01*
G01X1118494Y222447D02*
X1118161D01*
G01X1117186Y222172D02*
X1119076D01*
G01X1118761Y222054D02*
X1117186D01*
G01X1113652Y222014D02*
X1112767D01*
G01X1113603Y221880D02*
X1112816D01*
G01X1118761Y221857D02*
X1117186D01*
G01X1113603Y221808D02*
X1112816D01*
G01X1113652Y221660D02*
X1115572D01*
G01X1112816D02*
X1113603D01*
G01X1113652Y221621D02*
X1112767D01*
G01X1113603Y221463D02*
X1112816D01*
G01X1113013Y221266D02*
X1113406D01*
G01X1112816Y221092D02*
X1113603D01*
G01X1118761Y220873D02*
X1117186D01*
G01X1118761Y220558D02*
X1117895D01*
G01Y220203D02*
X1118761D01*
G01X1113406Y220085D02*
X1113013D01*
G01X1118761Y219888D02*
X1117186D01*
G01X1112816Y219722D02*
X1113603D01*
G01X1115572Y219691D02*
X1113652D01*
G01X1112816Y219543D02*
X1113603D01*
G01X1112816Y219471D02*
X1113603D01*
G01X1113652Y219101D02*
X1112767D01*
G01X1118761D02*
X1117186D01*
G01X1112816Y218588D02*
X1113603D01*
G01X1113454Y225163D02*
X1113586Y225191D01*
G01X1112965Y224220D02*
X1112833Y224192D01*
G01X1114843Y217787D02*
X1114602D01*
G01X1117053D02*
X1116852D01*
G01X1118862D02*
X1117897D01*
G01X1117857Y217582D02*
X1118621D01*
G01X1116852D02*
X1117053D01*
G01X1112816Y217386D02*
X1113603D01*
G01X1115968Y217171D02*
X1115807D01*
G01X1116531D02*
X1116330D01*
G01X1117053D02*
X1116852D01*
G01X1118621Y216966D02*
X1117857D01*
G01X1117897Y216720D02*
X1118621D01*
G01X1113603Y215951D02*
X1112816D01*
G01X1118621Y215858D02*
X1118862D01*
G01X1116330D02*
X1116531D01*
G01X1116852D02*
X1117053D01*
G01X1115405D02*
X1115606D01*
G01X1114602D02*
X1114843D01*
G01X1113603Y215361D02*
X1112816D01*
G01X1117897Y217787D02*
X1117696Y217746D01*
G01X1115807Y216966D02*
X1115968Y217007D01*
G01X1145002Y252511D02*
Y252566D01*
G01Y252354D02*
Y252511D01*
G01Y252099D02*
Y252354D01*
G01Y251758D02*
Y252099D01*
G01Y251334D02*
Y251758D01*
G01Y250860D02*
Y251334D01*
G01Y250345D02*
Y250860D01*
G01Y249810D02*
Y250345D01*
G01Y249965D02*
Y249810D01*
G01Y250112D02*
Y249965D01*
G01Y250247D02*
Y250112D01*
G01Y250366D02*
Y250247D01*
G01Y250465D02*
Y250366D01*
G01Y250538D02*
Y250465D01*
G01Y250582D02*
Y250538D01*
G01Y250597D02*
Y250582D01*
G01X1143033Y250581D02*
Y250597D01*
G01Y250536D02*
Y250581D01*
G01Y250464D02*
Y250536D01*
G01Y250366D02*
Y250464D01*
G01Y250245D02*
Y250366D01*
G01Y250110D02*
Y250245D01*
G01Y249962D02*
Y250110D01*
G01Y249810D02*
Y249962D01*
G01Y250354D02*
Y249810D01*
G01Y250869D02*
Y250354D01*
G01Y251343D02*
Y250869D01*
G01Y251758D02*
Y251343D01*
G01Y252105D02*
Y251758D01*
G01Y252357D02*
Y252105D01*
G01Y252513D02*
Y252357D01*
G01Y252566D02*
Y252513D01*
G01X1145002Y260455D02*
Y260440D01*
G01Y260500D02*
Y260455D01*
G01Y260573D02*
Y260500D01*
G01Y260670D02*
Y260573D01*
G01Y260791D02*
Y260670D01*
G01Y260927D02*
Y260791D01*
G01Y261074D02*
Y260927D01*
G01Y261227D02*
Y261074D01*
G01Y260682D02*
Y261227D01*
G01Y260168D02*
Y260682D01*
G01Y259693D02*
Y260168D01*
G01Y259278D02*
Y259693D01*
G01Y258931D02*
Y259278D01*
G01Y258679D02*
Y258931D01*
G01Y258523D02*
Y258679D01*
G01Y258471D02*
Y258523D01*
G01X1143033Y258525D02*
Y258471D01*
G01Y258682D02*
Y258525D01*
G01Y258937D02*
Y258682D01*
G01Y259278D02*
Y258937D01*
G01Y259702D02*
Y259278D01*
G01Y260177D02*
Y259702D01*
G01Y260692D02*
Y260177D01*
G01Y261227D02*
Y260692D01*
G01Y261071D02*
Y261227D01*
G01Y260924D02*
Y261071D01*
G01Y260789D02*
Y260924D01*
G01Y260670D02*
Y260789D01*
G01Y260571D02*
Y260670D01*
G01Y260499D02*
Y260571D01*
G01Y260455D02*
Y260499D01*
G01Y260440D02*
Y260455D01*
G01X1129253Y252511D02*
Y252566D01*
G01Y252354D02*
Y252511D01*
G01Y252099D02*
Y252354D01*
G01Y251758D02*
Y252099D01*
G01Y251334D02*
Y251758D01*
G01Y250860D02*
Y251334D01*
G01Y250345D02*
Y250860D01*
G01Y249810D02*
Y250345D01*
G01Y249965D02*
Y249810D01*
G01Y250112D02*
Y249965D01*
G01Y250247D02*
Y250112D01*
G01Y250366D02*
Y250247D01*
G01Y250465D02*
Y250366D01*
G01Y250538D02*
Y250465D01*
G01Y250582D02*
Y250538D01*
G01Y250597D02*
Y250582D01*
G01X1127285Y250581D02*
Y250597D01*
G01Y250536D02*
Y250581D01*
G01Y250464D02*
Y250536D01*
G01Y250366D02*
Y250464D01*
G01Y250245D02*
Y250366D01*
G01Y250110D02*
Y250245D01*
G01Y249962D02*
Y250110D01*
G01Y249810D02*
Y249962D01*
G01Y250354D02*
Y249810D01*
G01Y250869D02*
Y250354D01*
G01Y251343D02*
Y250869D01*
G01Y251758D02*
Y251343D01*
G01Y252105D02*
Y251758D01*
G01Y252357D02*
Y252105D01*
G01Y252513D02*
Y252357D01*
G01Y252566D02*
Y252513D01*
G01X1113505Y252511D02*
Y252566D01*
G01Y252354D02*
Y252511D01*
G01Y252099D02*
Y252354D01*
G01Y251758D02*
Y252099D01*
G01Y251334D02*
Y251758D01*
G01Y250860D02*
Y251334D01*
G01Y250345D02*
Y250860D01*
G01Y249810D02*
Y250345D01*
G01Y249965D02*
Y249810D01*
G01Y250112D02*
Y249965D01*
G01Y250247D02*
Y250112D01*
G01Y250366D02*
Y250247D01*
G01Y250465D02*
Y250366D01*
G01Y250538D02*
Y250465D01*
G01Y250582D02*
Y250538D01*
G01Y250597D02*
Y250582D01*
G01X1111537Y250581D02*
Y250597D01*
G01Y250536D02*
Y250581D01*
G01Y250464D02*
Y250536D01*
G01Y250366D02*
Y250464D01*
G01Y250245D02*
Y250366D01*
G01Y250110D02*
Y250245D01*
G01Y249962D02*
Y250110D01*
G01Y249810D02*
Y249962D01*
G01Y250354D02*
Y249810D01*
G01Y250869D02*
Y250354D01*
G01Y251343D02*
Y250869D01*
G01Y251758D02*
Y251343D01*
G01Y252105D02*
Y251758D01*
G01Y252357D02*
Y252105D01*
G01Y252513D02*
Y252357D01*
G01Y252566D02*
Y252513D01*
G01X1113505Y260455D02*
Y260440D01*
G01Y260500D02*
Y260455D01*
G01Y260573D02*
Y260500D01*
G01Y260670D02*
Y260573D01*
G01Y260791D02*
Y260670D01*
G01Y260927D02*
Y260791D01*
G01Y261074D02*
Y260927D01*
G01Y261227D02*
Y261074D01*
G01Y260682D02*
Y261227D01*
G01Y260168D02*
Y260682D01*
G01Y259693D02*
Y260168D01*
G01Y259278D02*
Y259693D01*
G01Y258931D02*
Y259278D01*
G01Y258679D02*
Y258931D01*
G01Y258523D02*
Y258679D01*
G01Y258471D02*
Y258523D01*
G01X1111537Y258525D02*
Y258471D01*
G01Y258682D02*
Y258525D01*
G01Y258937D02*
Y258682D01*
G01Y259278D02*
Y258937D01*
G01Y259702D02*
Y259278D01*
G01Y260177D02*
Y259702D01*
G01Y260692D02*
Y260177D01*
G01Y261227D02*
Y260692D01*
G01Y261071D02*
Y261227D01*
G01Y260924D02*
Y261071D01*
G01Y260789D02*
Y260924D01*
G01Y260670D02*
Y260789D01*
G01Y260571D02*
Y260670D01*
G01Y260499D02*
Y260571D01*
G01Y260455D02*
Y260499D01*
G01Y260440D02*
Y260455D01*
G01X1129253D02*
Y260440D01*
G01Y260500D02*
Y260455D01*
G01Y260573D02*
Y260500D01*
G01Y260670D02*
Y260573D01*
G01Y260791D02*
Y260670D01*
G01Y260927D02*
Y260791D01*
G01Y261074D02*
Y260927D01*
G01Y261227D02*
Y261074D01*
G01Y260682D02*
Y261227D01*
G01Y260168D02*
Y260682D01*
G01Y259693D02*
Y260168D01*
G01Y259278D02*
Y259693D01*
G01Y258931D02*
Y259278D01*
G01Y258679D02*
Y258931D01*
G01Y258523D02*
Y258679D01*
G01Y258471D02*
Y258523D01*
G01X1127285Y258525D02*
Y258471D01*
G01Y258682D02*
Y258525D01*
G01Y258937D02*
Y258682D01*
G01Y259278D02*
Y258937D01*
G01Y259702D02*
Y259278D01*
G01Y260177D02*
Y259702D01*
G01Y260692D02*
Y260177D01*
G01Y261227D02*
Y260692D01*
G01Y261071D02*
Y261227D01*
G01Y260924D02*
Y261071D01*
G01Y260789D02*
Y260924D01*
G01Y260670D02*
Y260789D01*
G01Y260571D02*
Y260670D01*
G01Y260499D02*
Y260571D01*
G01Y260455D02*
Y260499D01*
G01Y260440D02*
Y260455D01*
G01X1137128D02*
Y260440D01*
G01Y260500D02*
Y260455D01*
G01Y260573D02*
Y260500D01*
G01Y260670D02*
Y260573D01*
G01Y260791D02*
Y260670D01*
G01Y260927D02*
Y260791D01*
G01Y261074D02*
Y260927D01*
G01Y261227D02*
Y261074D01*
G01Y260682D02*
Y261227D01*
G01Y260168D02*
Y260682D01*
G01Y259693D02*
Y260168D01*
G01Y259278D02*
Y259693D01*
G01Y258931D02*
Y259278D01*
G01Y258679D02*
Y258931D01*
G01Y258523D02*
Y258679D01*
G01Y258471D02*
Y258523D01*
G01X1135159Y258525D02*
Y258471D01*
G01Y258682D02*
Y258525D01*
G01Y258937D02*
Y258682D01*
G01Y259278D02*
Y258937D01*
G01Y259702D02*
Y259278D01*
G01Y260177D02*
Y259702D01*
G01Y260692D02*
Y260177D01*
G01Y261227D02*
Y260692D01*
G01Y261071D02*
Y261227D01*
G01Y260924D02*
Y261071D01*
G01Y260789D02*
Y260924D01*
G01Y260670D02*
Y260789D01*
G01Y260571D02*
Y260670D01*
G01Y260499D02*
Y260571D01*
G01Y260455D02*
Y260499D01*
G01Y260440D02*
Y260455D01*
G01X1121379D02*
Y260440D01*
G01Y260500D02*
Y260455D01*
G01Y260573D02*
Y260500D01*
G01Y260670D02*
Y260573D01*
G01Y260791D02*
Y260670D01*
G01Y260927D02*
Y260791D01*
G01Y261074D02*
Y260927D01*
G01Y261227D02*
Y261074D01*
G01Y260682D02*
Y261227D01*
G01Y260168D02*
Y260682D01*
G01Y259693D02*
Y260168D01*
G01Y259278D02*
Y259693D01*
G01Y258931D02*
Y259278D01*
G01Y258679D02*
Y258931D01*
G01Y258523D02*
Y258679D01*
G01Y258471D02*
Y258523D01*
G01X1119411Y258525D02*
Y258471D01*
G01Y258682D02*
Y258525D01*
G01Y258937D02*
Y258682D01*
G01Y259278D02*
Y258937D01*
G01Y259702D02*
Y259278D01*
G01Y260177D02*
Y259702D01*
G01Y260692D02*
Y260177D01*
G01Y261227D02*
Y260692D01*
G01Y261071D02*
Y261227D01*
G01Y260924D02*
Y261071D01*
G01Y260789D02*
Y260924D01*
G01Y260670D02*
Y260789D01*
G01Y260571D02*
Y260670D01*
G01Y260499D02*
Y260571D01*
G01Y260455D02*
Y260499D01*
G01Y260440D02*
Y260455D01*
G01X1121379Y252511D02*
Y252566D01*
G01Y252354D02*
Y252511D01*
G01Y252099D02*
Y252354D01*
G01Y251758D02*
Y252099D01*
G01Y251334D02*
Y251758D01*
G01Y250860D02*
Y251334D01*
G01Y250345D02*
Y250860D01*
G01Y249810D02*
Y250345D01*
G01Y249965D02*
Y249810D01*
G01Y250112D02*
Y249965D01*
G01Y250247D02*
Y250112D01*
G01Y250366D02*
Y250247D01*
G01Y250465D02*
Y250366D01*
G01Y250538D02*
Y250465D01*
G01Y250582D02*
Y250538D01*
G01Y250597D02*
Y250582D01*
G01X1119411Y250581D02*
Y250597D01*
G01Y250536D02*
Y250581D01*
G01Y250464D02*
Y250536D01*
G01Y250366D02*
Y250464D01*
G01Y250245D02*
Y250366D01*
G01Y250110D02*
Y250245D01*
G01Y249962D02*
Y250110D01*
G01Y249810D02*
Y249962D01*
G01Y250354D02*
Y249810D01*
G01Y250869D02*
Y250354D01*
G01Y251343D02*
Y250869D01*
G01Y251758D02*
Y251343D01*
G01Y252105D02*
Y251758D01*
G01Y252357D02*
Y252105D01*
G01Y252513D02*
Y252357D01*
G01Y252566D02*
Y252513D01*
G01X1137128Y252511D02*
Y252566D01*
G01Y252354D02*
Y252511D01*
G01Y252099D02*
Y252354D01*
G01Y251758D02*
Y252099D01*
G01Y251334D02*
Y251758D01*
G01Y250860D02*
Y251334D01*
G01Y250345D02*
Y250860D01*
G01Y249810D02*
Y250345D01*
G01Y249965D02*
Y249810D01*
G01Y250112D02*
Y249965D01*
G01Y250247D02*
Y250112D01*
G01Y250366D02*
Y250247D01*
G01Y250465D02*
Y250366D01*
G01Y250538D02*
Y250465D01*
G01Y250582D02*
Y250538D01*
G01Y250597D02*
Y250582D01*
G01X1135159Y250581D02*
Y250597D01*
G01Y250536D02*
Y250581D01*
G01Y250464D02*
Y250536D01*
G01Y250366D02*
Y250464D01*
G01Y250245D02*
Y250366D01*
G01Y250110D02*
Y250245D01*
G01Y249962D02*
Y250110D01*
G01Y249810D02*
Y249962D01*
G01Y250354D02*
Y249810D01*
G01Y250869D02*
Y250354D01*
G01Y251343D02*
Y250869D01*
G01Y251758D02*
Y251343D01*
G01Y252105D02*
Y251758D01*
G01Y252357D02*
Y252105D01*
G01Y252513D02*
Y252357D01*
G01Y252566D02*
Y252513D01*
G01X1137324Y264971D02*
Y265361D01*
G01Y264604D02*
Y264971D01*
G01Y264266D02*
Y264604D01*
G01Y263969D02*
Y264266D01*
G01Y263721D02*
Y263969D01*
G01Y263541D02*
Y263721D01*
G01Y263430D02*
Y263541D01*
G01Y263392D02*
Y263430D01*
G01Y247605D02*
Y247644D01*
G01Y247493D02*
Y247605D01*
G01Y247311D02*
Y247493D01*
G01Y247068D02*
Y247311D01*
G01Y246765D02*
Y247068D01*
G01Y246426D02*
Y246765D01*
G01Y246058D02*
Y246426D01*
G01Y245676D02*
Y246058D01*
G01X1119214Y246065D02*
Y245676D01*
G01Y246432D02*
Y246065D01*
G01Y246771D02*
Y246432D01*
G01Y247068D02*
Y246771D01*
G01Y247315D02*
Y247068D01*
G01Y247495D02*
Y247315D01*
G01Y247606D02*
Y247495D01*
G01Y247644D02*
Y247606D01*
G01Y263431D02*
Y263392D01*
G01Y263543D02*
Y263431D01*
G01Y263725D02*
Y263543D01*
G01Y263969D02*
Y263725D01*
G01Y264271D02*
Y263969D01*
G01Y264610D02*
Y264271D01*
G01Y264978D02*
Y264610D01*
G01Y265361D02*
Y264978D01*
G01X1164326Y197533D02*
X1167213D01*
G01X1172265Y227369D02*
Y203812D01*
G01X1115985Y272538D02*
X1115680D01*
G01D02*
Y270512D01*
G01D02*
X1115375Y270876D01*
G01D02*
Y270460D01*
G01D02*
X1115680Y270097D01*
G01D02*
X1115985D01*
G01D02*
Y272538D01*
G01X1113799D02*
X1113544D01*
G01D02*
Y270876D01*
G01D02*
X1113799D01*
G01D02*
Y271136D01*
G01D02*
X1113900Y271032D01*
G01D02*
X1114053Y270928D01*
G01D02*
X1114256Y270876D01*
G01D02*
X1114460D01*
G01D02*
X1114612Y270928D01*
G01D02*
X1114765Y271032D01*
G01D02*
X1114866Y271136D01*
G01D02*
X1114917Y271292D01*
G01D02*
X1114968Y271551D01*
G01D02*
Y272538D01*
G01D02*
X1114714D01*
G01D02*
Y271551D01*
G01D02*
X1114663Y271292D01*
G01D02*
X1114561Y271188D01*
G01D02*
X1114460Y271136D01*
G01D02*
X1114256Y271084D01*
G01D02*
X1114053Y271136D01*
G01D02*
X1113900Y271240D01*
G01D02*
X1113799Y271343D01*
G01D02*
Y272538D01*
G01X1113137Y270357D02*
X1112883D01*
G01D02*
Y270097D01*
G01D02*
X1113137D01*
G01D02*
Y270357D01*
G01Y272538D02*
X1112883D01*
G01D02*
Y270876D01*
G01D02*
X1113137D01*
G01D02*
Y272538D01*
G01X1111866Y271136D02*
X1112019Y271084D01*
G01D02*
X1112120Y270980D01*
G01D02*
X1112171Y270824D01*
G01D02*
Y270668D01*
G01D02*
X1112120Y270512D01*
G01D02*
X1112019Y270408D01*
G01D02*
X1111866Y270357D01*
G01D02*
X1110900D01*
G01D02*
Y271136D01*
G01D02*
X1111866D01*
G01X1112476Y270668D02*
Y270876D01*
G01D02*
X1112426Y271032D01*
G01D02*
X1112273Y271240D01*
G01D02*
X1112070Y271395D01*
G01D02*
X1111815Y271447D01*
G01D02*
X1110900D01*
G01D02*
Y272538D01*
G01D02*
X1110595D01*
G01D02*
Y270097D01*
G01D02*
X1111815D01*
G01D02*
X1112070Y270149D01*
G01D02*
X1112273Y270305D01*
G01D02*
X1112426Y270512D01*
G01D02*
X1112476Y270668D01*
G01X1142049Y255518D02*
G03X1138112I-1968J0D01*
G01D02*
G03X1142049I1968J0D01*
G01X1118427D02*
G03X1114490I-1969J0D01*
G01D02*
G03X1118427I1968J0D01*
G01X1114490Y258471D02*
Y269298D01*
G01X1110553Y258471D02*
X1114490D01*
G01X1110553Y269298D02*
Y258471D01*
G01X1114490Y269298D02*
X1110553D01*
G01Y241739D02*
X1114490D01*
G01X1110553Y252566D02*
Y241739D01*
G01X1114490Y252566D02*
X1110553D01*
G01X1114490Y241739D02*
Y252566D01*
G01X1122364Y258471D02*
Y269298D01*
G01X1118427Y258471D02*
X1122364D01*
G01X1118427Y269298D02*
Y258471D01*
G01X1122364Y269298D02*
X1118427D01*
G01Y241739D02*
X1122364D01*
G01X1118427Y252566D02*
Y241739D01*
G01X1122364Y252566D02*
X1118427D01*
G01X1122364Y241739D02*
Y252566D01*
G01X1130238Y258471D02*
Y269298D01*
G01X1126301Y258471D02*
X1130238D01*
G01X1126301Y269298D02*
Y258471D01*
G01X1130238Y269298D02*
X1126301D01*
G01Y241739D02*
X1130238D01*
G01X1126301Y252566D02*
Y241739D01*
G01X1130238Y252566D02*
X1126301D01*
G01X1130238Y241739D02*
Y252566D01*
G01X1138112Y258471D02*
Y269298D01*
G01X1134175Y258471D02*
X1138112D01*
G01X1134175Y269298D02*
Y258471D01*
G01X1138112Y269298D02*
X1134175D01*
G01Y241739D02*
X1138112D01*
G01X1134175Y252566D02*
Y241739D01*
G01X1138112Y252566D02*
X1134175D01*
G01X1138112Y241739D02*
Y252566D01*
G01X1145986Y258471D02*
Y269298D01*
G01X1142049Y258471D02*
X1145986D01*
G01X1142049Y269298D02*
Y258471D01*
G01X1145986Y269298D02*
X1142049D01*
G01Y241739D02*
X1145986D01*
G01X1142049Y252566D02*
Y241739D01*
G01X1145986Y252566D02*
X1142049D01*
G01X1145986Y241739D02*
Y252566D01*
G01X1177928Y222251D02*
X1177518D01*
G01D02*
Y219570D01*
G01D02*
X1177928D01*
G01D02*
Y219821D01*
G01D02*
X1178092Y219654D01*
G01D02*
X1178338Y219570D01*
G01D02*
X1178666D01*
G01D02*
X1178913Y219654D01*
G01D02*
X1179159Y219905D01*
G01D02*
X1179405Y219654D01*
G01D02*
X1179651Y219570D01*
G01D02*
X1179979D01*
G01D02*
X1180225Y219654D01*
G01D02*
X1180389Y219821D01*
G01D02*
X1180553Y220240D01*
G01D02*
Y222251D01*
G01D02*
X1180143D01*
G01D02*
Y220240D01*
G01D02*
X1180061Y220073D01*
G01D02*
X1179979Y219989D01*
G01D02*
X1179815Y219905D01*
G01D02*
X1179568D01*
G01D02*
X1179405Y219989D01*
G01D02*
X1179322Y220073D01*
G01D02*
X1179241Y220240D01*
G01D02*
Y222251D01*
G01D02*
X1178830D01*
G01D02*
Y220240D01*
G01D02*
X1178748Y220073D01*
G01D02*
X1178666Y219989D01*
G01D02*
X1178502Y219905D01*
G01D02*
X1178338D01*
G01D02*
X1178092Y219989D01*
G01D02*
X1177928Y220156D01*
G01D02*
Y222251D01*
G01X1174237D02*
X1173827D01*
G01D02*
Y219570D01*
G01D02*
X1174237D01*
G01D02*
Y219821D01*
G01D02*
X1174401Y219654D01*
G01D02*
X1174647Y219570D01*
G01D02*
X1174976D01*
G01D02*
X1175222Y219654D01*
G01D02*
X1175468Y219905D01*
G01D02*
X1175714Y219654D01*
G01D02*
X1175960Y219570D01*
G01D02*
X1176288D01*
G01D02*
X1176534Y219654D01*
G01D02*
X1176698Y219821D01*
G01D02*
X1176862Y220240D01*
G01D02*
Y222251D01*
G01D02*
X1176452D01*
G01D02*
Y220240D01*
G01D02*
X1176370Y220073D01*
G01D02*
X1176288Y219989D01*
G01D02*
X1176124Y219905D01*
G01D02*
X1175878D01*
G01D02*
X1175714Y219989D01*
G01D02*
X1175631Y220073D01*
G01D02*
X1175550Y220240D01*
G01D02*
Y222251D01*
G01D02*
X1175139D01*
G01D02*
Y220240D01*
G01D02*
X1175057Y220073D01*
G01D02*
X1174976Y219989D01*
G01D02*
X1174811Y219905D01*
G01D02*
X1174647D01*
G01D02*
X1174401Y219989D01*
G01D02*
X1174237Y220156D01*
G01D02*
Y222251D01*
G01X1170628Y219989D02*
Y220575D01*
G01D02*
X1170710Y221078D01*
G01D02*
X1171039Y221580D01*
G01D02*
X1171285Y221748D01*
G01D02*
X1171694Y221832D01*
G01D02*
X1172105Y221748D01*
G01D02*
X1172351Y221580D01*
G01D02*
X1172679Y221078D01*
G01D02*
X1172761Y220575D01*
G01D02*
Y219989D01*
G01D02*
X1172679Y219486D01*
G01D02*
X1172351Y218984D01*
G01D02*
X1172105Y218816D01*
G01D02*
X1171694Y218732D01*
G01D02*
X1171285Y218816D01*
G01D02*
X1171039Y218984D01*
G01D02*
X1170710Y219486D01*
G01D02*
X1170628Y219989D01*
G01X1170300Y219486D02*
X1170218Y219905D01*
G01X1170382Y219235D02*
X1170300Y219486D01*
G01X1170546Y218900D02*
X1170382Y219235D01*
G01X1170792Y218649D02*
X1170546Y218900D01*
G01X1171202Y218397D02*
X1170792Y218649D01*
G01X1171694Y218314D02*
X1171202Y218397D01*
G01X1172187D02*
X1171694Y218314D01*
G01X1172597Y218649D02*
X1172187Y218397D01*
G01X1172843Y218900D02*
X1172597Y218649D01*
G01X1173007Y219235D02*
X1172843Y218900D01*
G01X1173089Y219486D02*
X1173007Y219235D01*
G01X1173171Y219905D02*
X1173089Y219486D01*
G01X1173171Y220659D02*
Y219905D01*
G01X1173089Y221078D02*
X1173171Y220659D01*
G01X1173007Y221329D02*
X1173089Y221078D01*
G01X1172843Y221664D02*
X1173007Y221329D01*
G01X1172597Y221915D02*
X1172843Y221664D01*
G01X1172187Y222167D02*
X1172597Y221915D01*
G01X1171694Y222251D02*
X1172187Y222167D01*
G01X1171202D02*
X1171694Y222251D01*
G01X1170792Y221915D02*
X1171202Y222167D01*
G01X1170546Y221664D02*
X1170792Y221915D01*
G01X1170382Y221329D02*
X1170546Y221664D01*
G01X1170300Y221078D02*
X1170382Y221329D01*
G01X1170218Y220659D02*
X1170300Y221078D01*
G01X1170218Y219905D02*
Y220659D01*
G01X1168250Y220575D02*
X1169562D01*
G01D02*
Y220910D01*
G01D02*
X1168250D01*
G01D02*
Y220575D01*
G01Y219570D02*
X1169562D01*
G01D02*
Y219905D01*
G01D02*
X1168250D01*
G01D02*
Y219570D01*
G01X1164805Y222251D02*
X1164313D01*
G01D02*
Y218314D01*
G01D02*
X1164805D01*
G01D02*
Y219905D01*
G01D02*
X1167102D01*
G01D02*
Y218314D01*
G01D02*
X1167594D01*
G01D02*
Y222251D01*
G01D02*
X1167102D01*
G01D02*
Y220408D01*
G01D02*
X1164805D01*
G01D02*
Y222251D01*
G01X1188013Y231306D02*
G03X1156517I-15748J0D01*
G01D02*
G03X1188013I15748J0D01*
G01X1189982Y215558D02*
Y269495D01*
G01D02*
G03X1186045Y273432I-3937J0D01*
G01Y211621D02*
G03X1189982Y215558I0J3937D01*
G01X1137324Y263392D02*
X1119214D01*
G01X1137324Y247644D02*
X1119214D01*
G01X1137128Y252566D02*
X1135159D01*
G01X1137128Y250597D02*
X1135159D01*
G01X1121379Y252566D02*
X1119411D01*
G01X1121379Y250597D02*
X1119411D01*
G01X1121379Y260440D02*
X1119411D01*
G01X1121379Y258471D02*
X1119411D01*
G01X1137128Y260440D02*
X1135159D01*
G01X1137128Y258471D02*
X1135159D01*
G01X1129253Y260440D02*
X1127285D01*
G01X1129253Y258471D02*
X1127285D01*
G01X1113505Y260440D02*
X1111537D01*
G01X1113505Y258471D02*
X1111537D01*
G01X1113505Y252566D02*
X1111537D01*
G01X1113505Y250597D02*
X1111537D01*
G01X1129253Y252566D02*
X1127285D01*
G01X1129253Y250597D02*
X1127285D01*
G01X1145002Y260440D02*
X1143033D01*
G01X1145002Y258471D02*
X1143033D01*
G01X1145002Y252566D02*
X1143033D01*
G01X1145002Y250597D02*
X1143033D01*
G01D02*
X1145002D01*
G01D02*
X1143033D01*
G01X1144411Y251188D02*
X1143624D01*
G01X1145002Y250597D02*
X1144411Y251188D01*
G01Y251975D02*
X1143624D01*
G01X1143033Y250597D02*
X1143624Y251188D01*
G01D02*
Y251975D01*
G01X1143033Y252566D02*
Y250597D01*
G01D02*
Y252566D01*
G01D02*
X1143624Y251975D01*
G01X1145002Y252566D02*
X1143033D01*
G01X1144411Y251975D02*
Y251188D01*
G01X1145002Y252566D02*
X1144411Y251975D01*
G01X1145002Y252566D02*
Y250597D01*
G01X1111537Y258471D02*
X1113505D01*
G01D02*
X1111537D01*
G01X1112128Y259062D02*
X1111537Y258471D01*
G01X1112915Y259062D02*
X1112128D01*
G01X1113505Y258471D02*
X1112915Y259062D01*
G01Y259849D02*
X1112128D01*
G01Y259062D02*
Y259849D01*
G01X1111537Y260440D02*
Y258471D01*
G01D02*
Y260440D01*
G01D02*
X1112128Y259849D01*
G01X1113505Y260440D02*
X1111537D01*
G01X1112915Y259849D02*
Y259062D01*
G01X1113505Y260440D02*
X1112915Y259849D01*
G01X1113505Y260440D02*
Y258471D01*
G01X1111537Y250597D02*
X1113505D01*
G01D02*
X1111537D01*
G01X1112915Y251188D02*
X1112128D01*
G01X1113505Y250597D02*
X1112915Y251188D01*
G01Y251975D02*
X1112128D01*
G01X1111537Y250597D02*
X1112128Y251188D01*
G01D02*
Y251975D01*
G01X1111537Y252566D02*
Y250597D01*
G01D02*
Y252566D01*
G01D02*
X1112128Y251975D01*
G01X1113505Y252566D02*
X1111537D01*
G01X1112915Y251975D02*
Y251188D01*
G01X1113505Y252566D02*
X1112915Y251975D01*
G01X1113505Y252566D02*
Y250597D01*
G01X1135159Y260440D02*
X1137128D01*
G01X1135159D02*
Y258471D01*
G01D02*
X1137128D01*
G01Y260440D02*
Y258471D01*
G01X1135159Y250597D02*
X1137128D01*
G01X1135159Y252566D02*
Y250597D01*
G01Y252566D02*
X1137128D01*
G01X1119411Y260440D02*
X1121379D01*
G01X1119411D02*
Y258471D01*
G01D02*
X1121379D01*
G01Y260440D02*
Y258471D01*
G01X1119411Y252566D02*
X1121379D01*
G01X1119411D02*
Y250597D01*
G01D02*
X1121379D01*
G01Y252566D02*
Y250597D01*
G01X1127285Y260440D02*
X1129253D01*
G01X1127285D02*
Y258471D01*
G01D02*
X1129253D01*
G01Y260440D02*
Y258471D01*
G01X1127285Y252566D02*
X1129253D01*
G01X1127285D02*
Y250597D01*
G01D02*
X1129253D01*
G01Y252566D02*
Y250597D01*
G01X1119214Y265361D02*
X1137324D01*
G01Y263392D02*
X1119214D01*
G01Y267428D02*
X1137324D01*
G01D02*
Y265361D01*
G01X1119214Y268018D02*
X1137324D01*
G01X1119214D02*
X1137324D01*
G01X1119214Y243018D02*
X1137324D01*
G01D02*
Y268018D01*
G01X1119214Y243018D02*
X1137324D01*
G01X1119214Y243609D02*
X1137324D01*
G01Y245676D02*
Y243609D01*
G01X1119214Y247644D02*
X1137324D01*
G01Y245676D02*
X1119214D01*
G01Y247644D02*
X1137324D01*
G01X1119214Y267428D02*
Y265361D01*
G01Y268018D02*
Y267428D01*
G01Y243018D02*
Y268018D01*
G01Y243609D02*
Y243018D01*
G01Y245676D02*
Y243609D01*
G01Y263392D02*
Y247644D01*
G01X1137324Y243018D02*
Y243609D01*
G01Y267428D02*
Y268018D01*
G01X1135159Y258471D02*
X1137128D01*
G01X1135159Y260440D02*
Y258471D01*
G01Y250597D02*
X1137128D01*
G01X1135159Y252566D02*
Y250597D01*
G01X1119411Y258471D02*
X1121379D01*
G01X1119411Y260440D02*
Y258471D01*
G01Y250597D02*
X1121379D01*
G01X1119411Y252566D02*
Y250597D01*
G01X1127285Y258471D02*
X1129253D01*
G01X1127285Y260440D02*
Y258471D01*
G01Y250597D02*
X1129253D01*
G01X1127285Y252566D02*
Y250597D01*
G01X1119214Y263392D02*
X1137324D01*
G01D02*
Y247644D01*
G01X1137128Y252566D02*
Y250597D01*
G01X1143033Y258471D02*
X1145002D01*
G01D02*
X1143033D01*
G01X1143624Y259062D02*
X1143033Y258471D01*
G01X1144411Y259062D02*
X1143624D01*
G01X1145002Y258471D02*
X1144411Y259062D01*
G01Y259849D02*
X1143624D01*
G01Y259062D02*
Y259849D01*
G01X1143033Y260440D02*
Y258471D01*
G01D02*
Y260440D01*
G01D02*
X1143624Y259849D01*
G01X1145002Y260440D02*
X1143033D01*
G01X1144411Y259849D02*
Y259062D01*
G01X1145002Y260440D02*
X1144411Y259849D01*
G01X1145002Y260440D02*
Y258471D01*
G01X1148053Y264377D02*
Y265361D01*
G01D02*
X1145592D01*
G01D02*
Y264377D01*
G01X1142442D02*
Y265361D01*
G01D02*
X1137718D01*
G01D02*
Y264377D01*
G01X1134568D02*
Y265361D01*
G01D02*
X1129844D01*
G01D02*
Y264377D01*
G01X1126694D02*
Y265361D01*
G01D02*
X1121970D01*
G01D02*
Y264377D01*
G01X1118820D02*
Y265361D01*
G01X1110946Y264377D02*
Y265361D01*
G01X1114096D02*
Y264377D01*
G01X1118820Y265361D02*
X1114096D01*
G01X1110946Y264377D02*
X1114096D01*
G01X1148053D02*
X1149628D01*
G01X1142442D02*
X1145592D01*
G01X1134568D02*
X1137718D01*
G01X1126694D02*
X1129844D01*
G01X1118820D02*
X1121970D01*
G01X1151990Y266739D02*
X1149628Y264377D01*
G01D02*
Y256109D01*
G01X1145592Y246660D02*
X1142442D01*
G01X1145592D02*
Y245676D01*
G01D02*
X1148053D01*
G01D02*
Y246660D01*
G01X1149628D02*
X1148053D01*
G01X1151990Y248629D02*
X1149628Y250991D01*
G01D02*
Y246660D01*
G01X1153171Y250991D02*
X1149628D01*
G01X1135159Y252566D02*
X1137128D01*
G01X1135159D02*
X1137128D01*
G01Y249810D02*
X1135159D01*
G01X1137128D02*
Y247447D01*
G01D02*
X1135159D01*
G01X1135750Y245085D02*
X1135159Y247447D01*
G01X1136537Y245085D02*
X1135750D01*
G01X1137128Y247447D02*
X1136537Y245085D01*
G01D02*
X1135750D01*
G01X1135159Y249810D02*
Y247447D01*
G01Y250597D02*
Y252566D01*
G01Y247447D02*
Y249810D01*
G01D02*
X1137128D01*
G01Y250597D02*
X1135159D01*
G01X1137128Y247447D02*
Y249810D01*
G01X1135159Y247447D02*
X1135750Y245085D01*
G01X1137128Y247447D02*
X1135159D01*
G01X1137128D02*
X1136537Y245085D01*
G01X1135159Y250597D02*
X1137128D01*
G01D02*
Y252566D01*
G01X1133584Y250400D02*
Y254534D01*
G01X1138702Y250400D02*
X1133584D01*
G01Y254534D02*
X1138702D01*
G01X1119411Y252566D02*
X1121379D01*
G01X1119411D02*
X1121379D01*
G01Y249810D02*
X1119411D01*
G01X1121379D02*
Y247447D01*
G01D02*
X1119411D01*
G01X1120002Y245085D02*
X1119411Y247447D01*
G01X1120789Y245085D02*
X1120002D01*
G01X1121379Y247447D02*
X1120789Y245085D01*
G01D02*
X1120002D01*
G01X1119411Y249810D02*
Y247447D01*
G01Y250597D02*
Y252566D01*
G01Y247447D02*
Y249810D01*
G01D02*
X1121379D01*
G01Y250597D02*
X1119411D01*
G01X1121379Y247447D02*
Y249810D01*
G01X1119411Y247447D02*
X1120002Y245085D01*
G01X1121379Y247447D02*
X1119411D01*
G01X1121379D02*
X1120789Y245085D01*
G01X1119411Y250597D02*
X1121379D01*
G01D02*
Y252566D01*
G01X1117836Y250400D02*
Y254534D01*
G01X1122954Y250400D02*
X1117836D01*
G01Y254534D02*
X1122954D01*
G01X1119411Y260440D02*
X1121379D01*
G01X1119411D02*
X1121379D01*
G01Y261227D02*
X1119411D01*
G01X1121379D02*
Y263589D01*
G01D02*
X1119411D01*
G01X1120002Y265951D02*
X1119411Y263589D01*
G01X1120789Y265951D02*
X1120002D01*
G01X1121379Y263589D02*
X1120789Y265951D01*
G01D02*
X1120002D01*
G01X1119411Y261227D02*
Y263589D01*
G01Y258471D02*
Y260440D01*
G01Y263589D02*
Y261227D01*
G01D02*
X1121379D01*
G01Y258471D02*
X1119411D01*
G01X1121379Y263589D02*
Y261227D01*
G01X1119411Y263589D02*
X1120002Y265951D01*
G01X1121379Y263589D02*
X1119411D01*
G01X1121379D02*
X1120789Y265951D01*
G01X1119411Y258471D02*
X1121379D01*
G01D02*
Y260440D01*
G01X1117836Y256503D02*
Y260636D01*
G01Y256503D02*
X1138702D01*
G01X1117836Y254534D02*
Y256503D01*
G01X1138702Y254534D02*
X1117836D01*
G01X1138702Y256503D02*
Y254534D01*
G01X1135159Y260440D02*
X1137128D01*
G01X1135159D02*
X1137128D01*
G01Y261227D02*
X1135159D01*
G01X1137128D02*
Y263589D01*
G01D02*
X1135159D01*
G01X1135750Y265951D02*
X1135159Y263589D01*
G01X1136537Y265951D02*
X1135750D01*
G01X1137128Y263589D02*
X1136537Y265951D01*
G01D02*
X1135750D01*
G01X1135159Y261227D02*
Y263589D01*
G01Y258471D02*
Y260440D01*
G01Y263589D02*
Y261227D01*
G01D02*
X1137128D01*
G01Y258471D02*
X1135159D01*
G01X1137128Y263589D02*
Y261227D01*
G01X1135159Y263589D02*
X1135750Y265951D01*
G01X1137128Y263589D02*
X1135159D01*
G01X1137128D02*
X1136537Y265951D01*
G01X1135159Y258471D02*
X1137128D01*
G01D02*
Y260440D01*
G01X1133584Y256503D02*
Y260636D01*
G01X1138702D02*
X1133584D01*
G01Y263392D02*
X1138702D01*
G01X1133584D02*
Y260636D01*
G01Y256503D02*
Y263392D01*
G01X1127285Y260440D02*
X1129253D01*
G01X1127285D02*
X1129253D01*
G01Y261227D02*
X1127285D01*
G01X1129253D02*
Y263589D01*
G01D02*
X1127285D01*
G01X1127876Y265951D02*
X1127285Y263589D01*
G01X1128663Y265951D02*
X1127876D01*
G01X1129253Y263589D02*
X1128663Y265951D01*
G01D02*
X1127876D01*
G01X1127285Y261227D02*
Y263589D01*
G01Y258471D02*
Y260440D01*
G01Y263589D02*
Y261227D01*
G01D02*
X1129253D01*
G01Y258471D02*
X1127285D01*
G01X1129253Y263589D02*
Y261227D01*
G01X1127285Y263589D02*
X1127876Y265951D01*
G01X1129253Y263589D02*
X1127285D01*
G01X1129253D02*
X1128663Y265951D01*
G01X1130828Y260636D02*
X1125710D01*
G01Y263392D02*
X1130828D01*
G01X1122954Y256503D02*
Y263392D01*
G01X1125710D02*
Y260636D01*
G01Y256503D02*
Y263392D01*
G01X1127285Y258471D02*
X1129253D01*
G01D02*
Y260440D01*
G01X1125710Y256503D02*
Y260636D01*
G01X1130828D02*
Y263392D01*
G01Y256503D02*
Y260636D01*
G01Y256503D02*
Y263392D01*
G01X1125710Y256503D02*
X1130828D01*
G01X1122954D02*
X1125710D01*
G01X1117836D02*
X1122954D01*
G01X1133584D02*
X1138702D01*
G01X1130828D02*
X1133584D01*
G01X1122954Y260636D02*
Y263392D01*
G01Y256503D02*
Y260636D01*
G01D02*
X1117836D01*
G01Y263392D02*
X1122954D01*
G01X1111537Y260440D02*
X1113505D01*
G01X1111537D02*
X1113505D01*
G01Y261227D02*
X1111537D01*
G01X1113505D02*
Y263589D01*
G01D02*
X1111537D01*
G01X1112128Y265951D02*
X1111537Y263589D01*
G01X1112915Y265951D02*
X1112128D01*
G01X1113505Y263589D02*
X1112915Y265951D01*
G01D02*
X1112128D01*
G01X1111537Y261227D02*
Y263589D01*
G01Y258471D02*
Y260440D01*
G01Y263589D02*
Y261227D01*
G01D02*
X1113505D01*
G01Y258471D02*
X1111537D01*
G01X1113505Y263589D02*
Y261227D01*
G01X1111537Y263589D02*
X1112128Y265951D01*
G01X1113505Y263589D02*
X1111537D01*
G01X1113505D02*
X1112915Y265951D01*
G01X1111537Y252566D02*
X1113505D01*
G01X1111537D02*
X1113505D01*
G01Y249810D02*
X1111537D01*
G01X1113505D02*
Y247447D01*
G01D02*
X1111537D01*
G01X1112128Y245085D02*
X1111537Y247447D01*
G01X1112915Y245085D02*
X1112128D01*
G01X1113505Y247447D02*
X1112915Y245085D01*
G01D02*
X1112128D01*
G01X1111537Y249810D02*
Y247447D01*
G01Y250597D02*
Y252566D01*
G01Y247447D02*
Y249810D01*
G01D02*
X1113505D01*
G01Y250597D02*
X1111537D01*
G01X1113505Y247447D02*
Y249810D01*
G01X1111537Y247447D02*
X1112128Y245085D01*
G01X1113505Y247447D02*
X1111537D01*
G01X1113505D02*
X1112915Y245085D01*
G01X1117836Y256467D02*
G03X1116458Y257192I-1378J-947D01*
G01X1115080Y256467D02*
Y263392D01*
G01X1116458Y257192D02*
G03X1115080Y256467I0J-1672D01*
G01Y260636D02*
Y263392D01*
G01Y256467D02*
Y260636D01*
G01D02*
X1109962D01*
G01Y263392D02*
X1115080D01*
G01X1111537Y258471D02*
X1113505D01*
G01D02*
Y260440D01*
G01X1111537Y250597D02*
X1113505D01*
G01D02*
Y252566D01*
G01X1109962Y250400D02*
Y260636D01*
G01X1115080Y250400D02*
X1109962D01*
G01X1115080Y256467D02*
G03Y254569I1378J-949D01*
G01Y250400D02*
Y254569D01*
G01Y247644D02*
Y250400D01*
G01Y254569D02*
G03X1116458Y253845I1378J949D01*
G01X1115080Y247644D02*
Y254569D01*
G01X1116458Y253845D02*
G03X1117836Y254569I0J1673D01*
G01X1116458Y253845D02*
G03Y257192I0J1674D01*
G01Y254436D02*
G03Y256601I0J1082D01*
G01D02*
G03Y254436I0J-1083D01*
G01Y257192D02*
G03Y253845I0J-1674D01*
G01X1117836Y254569D02*
G03Y256467I-1378J949D01*
G01D02*
Y254569D01*
G01Y247644D02*
Y254569D01*
G01Y250400D02*
Y247644D01*
G01Y263392D02*
Y260636D01*
G01Y256467D02*
Y263392D01*
G01X1122954Y250400D02*
Y254534D01*
G01Y247644D02*
Y250400D01*
G01X1127285Y252566D02*
X1129253D01*
G01X1127285D02*
X1129253D01*
G01Y249810D02*
X1127285D01*
G01X1129253D02*
Y247447D01*
G01D02*
X1127285D01*
G01X1127876Y245085D02*
X1127285Y247447D01*
G01X1128663Y245085D02*
X1127876D01*
G01X1129253Y247447D02*
X1128663Y245085D01*
G01D02*
X1127876D01*
G01X1127285Y249810D02*
Y247447D01*
G01Y250597D02*
Y252566D01*
G01Y247447D02*
Y249810D01*
G01D02*
X1129253D01*
G01Y250597D02*
X1127285D01*
G01X1129253Y247447D02*
Y249810D01*
G01X1127285Y247447D02*
X1127876Y245085D01*
G01X1129253Y247447D02*
X1127285D01*
G01X1129253D02*
X1128663Y245085D01*
G01X1130828Y247644D02*
Y254534D01*
G01Y250400D02*
Y254534D01*
G01Y247644D02*
Y250400D01*
G01X1127285Y250597D02*
X1129253D01*
G01D02*
Y252566D01*
G01X1125710Y250400D02*
Y254534D01*
G01X1130828Y250400D02*
X1125710D01*
G01Y254534D02*
X1130828D01*
G01X1125710Y247644D02*
Y254534D01*
G01Y250400D02*
Y247644D01*
G01X1122954D02*
Y254534D01*
G01X1133584D02*
X1130828D01*
G01X1125710D02*
X1122954D01*
G01X1133584Y247644D02*
Y254534D01*
G01Y250400D02*
Y247644D01*
G01X1138702Y256467D02*
G03Y254569I1378J-949D01*
G01X1143033Y260440D02*
X1145002D01*
G01X1143033D02*
X1145002D01*
G01Y261227D02*
X1143033D01*
G01X1145002D02*
Y263589D01*
G01D02*
X1143033D01*
G01X1143624Y265951D02*
X1143033Y263589D01*
G01X1144411Y265951D02*
X1143624D01*
G01X1145002Y263589D02*
X1144411Y265951D01*
G01D02*
X1143624D01*
G01X1143033Y261227D02*
Y263589D01*
G01D02*
Y261227D01*
G01D02*
X1145002D01*
G01Y258471D02*
X1143033D01*
G01X1145002Y263589D02*
Y261227D01*
G01X1143033Y263589D02*
X1143624Y265951D01*
G01X1145002Y263589D02*
X1143033D01*
G01X1145002D02*
X1144411Y265951D01*
G01X1145002Y260440D02*
Y258471D01*
G01X1143033Y252566D02*
X1145002D01*
G01X1143033D02*
X1145002D01*
G01Y249810D02*
X1143033D01*
G01X1145002D02*
Y247447D01*
G01D02*
X1143033D01*
G01X1143624Y245085D02*
X1143033Y247447D01*
G01X1144411Y245085D02*
X1143624D01*
G01X1145002Y247447D02*
X1144411Y245085D01*
G01D02*
X1143624D01*
G01X1143033Y249810D02*
Y247447D01*
G01D02*
Y249810D01*
G01D02*
X1145002D01*
G01Y250597D02*
X1143033D01*
G01X1145002Y247447D02*
Y249810D01*
G01X1143033Y247447D02*
X1143624Y245085D01*
G01X1145002Y247447D02*
X1143033D01*
G01X1145002D02*
X1144411Y245085D01*
G01X1145002Y252566D02*
Y250597D01*
G01X1143033Y258471D02*
X1145002D01*
G01X1143033Y260440D02*
Y258471D01*
G01Y250597D02*
X1145002D01*
G01X1143033Y252566D02*
Y250597D01*
G01X1141458Y250400D02*
Y254569D01*
G01X1146576Y250400D02*
X1141458D01*
G01Y256467D02*
Y260636D01*
G01Y254569D02*
G03Y256467I-1378J949D01*
G01X1146576Y260636D02*
X1141458D01*
G01Y263392D02*
X1146576D01*
G01X1141458D02*
Y260636D01*
G01Y256467D02*
Y263392D01*
G01Y256467D02*
G03X1140080Y257192I-1378J-947D01*
G01X1138702Y256467D02*
Y263392D01*
G01X1140080Y257192D02*
G03X1138702Y256467I0J-1672D01*
G01Y260636D02*
Y263392D01*
G01Y256503D02*
Y260636D01*
G01Y250400D02*
Y254534D01*
G01Y247644D02*
Y250400D01*
G01Y256467D02*
Y254569D01*
G01D02*
G03X1140080Y253845I1378J949D01*
G01X1138702Y247644D02*
Y254569D01*
G01X1140080Y253845D02*
G03X1141458Y254569I0J1673D01*
G01X1140080Y253845D02*
G03Y257192I0J1674D01*
G01Y254436D02*
G03Y256601I0J1082D01*
G01D02*
G03Y254436I0J-1083D01*
G01Y257192D02*
G03Y253845I0J-1674D01*
G01X1141458Y247644D02*
Y254569D01*
G01Y250400D02*
Y247644D01*
G01X1146576Y260636D02*
Y263392D01*
G01Y250400D02*
Y260636D01*
G01Y247644D02*
Y250400D01*
G01X1117836Y263392D02*
X1115080D01*
G01X1125710D02*
X1122954D01*
G01X1133584D02*
X1130828D01*
G01X1141458D02*
X1138702D01*
G01X1149923D02*
X1146576D01*
G01X1109962Y250400D02*
Y247644D01*
G01Y263392D02*
Y260636D01*
G01Y247644D02*
Y263392D01*
G01X1146576Y247644D02*
X1149923D01*
G01X1141458D02*
X1146576D01*
G01X1138702D02*
X1141458D01*
G01X1133584D02*
X1138702D01*
G01X1130828D02*
X1133584D01*
G01X1125710D02*
X1130828D01*
G01X1122954D02*
X1125710D01*
G01X1117836D02*
X1122954D01*
G01X1115080D02*
X1117836D01*
G01X1109962D02*
X1115080D01*
G01X1146576D02*
Y263392D01*
G01X1149923Y247644D02*
Y263392D01*
G01X1134175Y243117D02*
X1132206D01*
G01X1134175Y245676D02*
Y243117D01*
G01X1132206Y245676D02*
Y243117D01*
G01D02*
X1124332D01*
G01X1132206Y245676D02*
Y243117D01*
G01X1124332Y245676D02*
Y243117D01*
G01D02*
X1122364D01*
G01X1124332Y245676D02*
Y243117D01*
G01X1122364Y245676D02*
Y243117D01*
G01X1121773Y246660D02*
X1134765D01*
G01X1121921D02*
X1121773D01*
G01X1134765D02*
X1134618D01*
G01X1134765D02*
Y243117D01*
G01X1134618Y245676D02*
Y246660D01*
G01X1149923Y247644D02*
Y263392D01*
G01X1121773Y246660D02*
Y243117D01*
G01X1143328Y243510D02*
X1145297D01*
G01X1141360D02*
X1143328D01*
G01X1141360D02*
Y243117D01*
G01X1153171D02*
X1145297D01*
G01X1134765D02*
X1153171D01*
G01X1134175D02*
X1134765D01*
G01X1121773D02*
X1122364D01*
G01X1143328D02*
X1141360D01*
G01X1145297D02*
X1143328D01*
G01Y243510D02*
Y243117D01*
G01X1141360Y243510D02*
X1145297D01*
G01X1151990Y248629D02*
Y244298D01*
G01X1153171Y248629D02*
X1151990D01*
G01X1153171Y243117D02*
Y248629D01*
G01X1145297Y243510D02*
Y243117D01*
G01X1110946Y245676D02*
Y246660D01*
G01X1145592D02*
X1142442D01*
G01X1149628D02*
X1148053D01*
G01X1151990Y244298D02*
X1149628Y246660D01*
G01X1114096D02*
X1110946D01*
G01X1142442Y245676D02*
Y246660D01*
G01X1114096Y245676D02*
X1142442D01*
G01X1122364D02*
X1121921D01*
G01X1124332D02*
X1122364D01*
G01X1132206D02*
X1124332D01*
G01X1134175D02*
X1132206D01*
G01X1134618D02*
X1134175D01*
G01X1114096Y246660D02*
Y245676D01*
G01Y246660D02*
X1110946D01*
G01X1143033Y252566D02*
X1145002D01*
G01D02*
Y250597D01*
G01X1111537Y260440D02*
X1113505D01*
G01D02*
Y258471D01*
G01X1111537Y252566D02*
X1113505D01*
G01D02*
Y250597D01*
G01X1119411Y260440D02*
X1121379D01*
G01D02*
Y258471D01*
G01X1119411Y252566D02*
X1121379D01*
G01D02*
Y250597D01*
G01X1127285Y260440D02*
X1129253D01*
G01D02*
Y258471D01*
G01X1127285Y252566D02*
X1129253D01*
G01D02*
Y250597D01*
G01X1135159Y260440D02*
X1137128D01*
G01D02*
Y258471D01*
G01X1135159Y252566D02*
X1137128D01*
G01D02*
Y250597D01*
G01X1143033Y260440D02*
X1145002D01*
G01D02*
Y258471D01*
G01X1110946Y245676D02*
Y246660D01*
G01Y264377D02*
Y265361D01*
G01X1114096Y264377D02*
X1110946D01*
G01X1114096Y265361D02*
Y264377D01*
G01X1118820Y265361D02*
X1114096D01*
G01X1118820Y264377D02*
Y265361D01*
G01X1121970Y264377D02*
X1118820D01*
G01X1121970Y265361D02*
Y264377D01*
G01X1126694Y265361D02*
X1121970D01*
G01X1126694Y264377D02*
Y265361D01*
G01X1129844Y264377D02*
X1126694D01*
G01X1129844Y265361D02*
Y264377D01*
G01X1134568Y265361D02*
X1129844D01*
G01X1134568Y264377D02*
Y265361D01*
G01X1137718Y264377D02*
X1134568D01*
G01X1137718Y265361D02*
Y264377D01*
G01X1142442Y265361D02*
X1137718D01*
G01X1142442Y264377D02*
Y265361D01*
G01X1145592Y264377D02*
X1142442D01*
G01X1145592Y265361D02*
Y264377D01*
G01X1148053Y265361D02*
X1145592D01*
G01X1148053Y264377D02*
Y265361D01*
G01X1149628Y264377D02*
X1148053D01*
G01X1149628Y256109D02*
Y264377D01*
G01X1153171Y256109D02*
X1149628D01*
G01Y250991D02*
X1153171D01*
G01X1149628Y246660D02*
Y250991D01*
G01X1148053Y245676D02*
Y246660D01*
G01X1145592Y245676D02*
X1148053D01*
G01X1145592Y246660D02*
Y245676D01*
G01X1142442D02*
Y246660D01*
G01X1134618Y245676D02*
X1142442D01*
G01X1121921Y246660D02*
X1134618D01*
G01X1121921Y245676D02*
Y246660D01*
G01X1114096Y245676D02*
X1121921D01*
G01X1114096Y246660D02*
Y245676D01*
G01X1151990Y266739D02*
Y258471D01*
G01X1153171D02*
Y267920D01*
G01X1151990Y258471D02*
X1153171D01*
G01X1149628Y256109D02*
X1153171D01*
G01X1151990Y258471D02*
X1149628Y256109D01*
G01X1153171Y243117D02*
Y267920D01*
G01Y250991D02*
Y248629D01*
G01Y256109D02*
Y250991D01*
G01Y258471D02*
Y256109D01*
G01X1187890Y229337D02*
X1181909D01*
G01X1174234Y221662D02*
G03X1181909Y229337I-1969J9644D01*
G01X1174234Y221662D02*
Y215681D01*
G01X1170297D02*
Y221662D01*
G01X1162622Y229337D02*
G03X1170297Y221662I9644J1969D01*
G01X1162622Y229337D02*
X1156641D01*
G01Y233274D02*
X1162622D01*
G01X1170297Y240949D02*
G03X1162622Y233274I1968J-9643D01*
G01X1170297Y240949D02*
Y246930D01*
G01X1174234D02*
Y240949D01*
G01X1181909Y233274D02*
G03X1174234Y240949I-9644J-1969D01*
G01X1181909Y233274D02*
X1187890D01*
G01X1162423Y231306D02*
G03X1182108I9843J0D01*
G01D02*
G03X1162423I-9842J0D01*
G01X1170297Y215681D02*
G03X1174234I1969J15625D01*
G01X1187890Y229337D02*
G03X1188013Y231306I-15625J1964D01*
G01X1156517D02*
G03X1156641Y229337I15741J3D01*
G01X1174234Y246930D02*
G03X1170297I-1968J-15624D01*
G01X1156641Y233274D02*
G03X1156517Y231306I15624J-1972D01*
G01X1188013D02*
G03X1187890Y233274I-15748J4D01*
G01X1180533Y231306D02*
G03X1163998I-8267J0D01*
G01D02*
G03X1180533I8268J0D01*
G01X1174234Y221662D02*
G03X1181909Y229337I-1969J9644D01*
G01X1187890D02*
X1181909D01*
G01X1174234Y215681D02*
G03X1187890Y229337I-1969J15625D01*
G01X1174234Y221662D02*
Y215681D01*
G01X1162622Y229337D02*
G03X1170297Y221662I9644J1969D01*
G01Y215681D02*
Y221662D01*
G01X1156641Y229337D02*
G03X1170297Y215681I15625J1969D01*
G01X1162622Y229337D02*
X1156641D01*
G01X1170297Y240949D02*
G03X1162622Y233274I1968J-9643D01*
G01X1156641D02*
X1162622D01*
G01X1170297Y246930D02*
G03X1156641Y233274I1968J-15624D01*
G01X1170297Y240949D02*
Y246930D01*
G01X1187890Y233274D02*
G03X1174234Y246930I-15625J-1969D01*
G01X1181909Y233274D02*
X1187890D01*
G01X1181909D02*
G03X1174234Y240949I-9644J-1969D01*
G01Y246930D02*
Y240949D01*
G01X1182362Y224908D02*
G03X1184331I984J0D01*
G01D02*
G03X1182362I-984J0D01*
G01X1177679Y220225D02*
G03X1179647I984J0D01*
G01D02*
G03X1177679I-984J0D01*
G01X1160200Y224908D02*
G03X1162168I984J0D01*
G01D02*
G03X1160200I-984J0D01*
G01X1164883Y220225D02*
G03X1166852I984J0D01*
G01D02*
G03X1164883I-985J0D01*
G01X1182362Y237703D02*
G03X1184331I984J0D01*
G01D02*
G03X1182362I-984J0D01*
G01X1177679Y242386D02*
G03X1179647I984J0D01*
G01D02*
G03X1177679I-984J0D01*
G01X1160200Y237703D02*
G03X1162168I984J0D01*
G01D02*
G03X1160200I-984J0D01*
G01X1164883Y242386D02*
G03X1166852I984J0D01*
G01D02*
G03X1164883I-985J0D01*
G01X1182362Y224908D02*
G03X1184331I984J0D01*
G01D02*
G03X1182362I-984J0D01*
G01X1177679Y220225D02*
G03X1179647I984J0D01*
G01D02*
G03X1177679I-984J0D01*
G01X1160200Y224908D02*
G03X1162168I984J0D01*
G01D02*
G03X1160200I-984J0D01*
G01X1164883Y220225D02*
G03X1166852I984J0D01*
G01D02*
G03X1164883I-985J0D01*
G01X1182362Y237703D02*
G03X1184331I984J0D01*
G01D02*
G03X1182362I-984J0D01*
G01X1177679Y242386D02*
G03X1179647I984J0D01*
G01D02*
G03X1177679I-984J0D01*
G01X1160200Y237703D02*
G03X1162168I984J0D01*
G01D02*
G03X1160200I-984J0D01*
G01X1164883Y242386D02*
G03X1166852I984J0D01*
G01D02*
G03X1164883I-985J0D01*
G01X1156517Y231306D02*
G03X1188013I15748J0D01*
G01D02*
G03X1156517I-15748J0D01*
G01X1180533D02*
G03X1163998I-8267J0D01*
G01D02*
G03X1180533I8268J0D01*
G01D02*
G03X1163998I-8267J0D01*
G01D02*
G03X1180533I8268J0D01*
G01X1182362Y224908D02*
G03X1184331I984J0D01*
G01D02*
G03X1182362I-984J0D01*
G01X1177679Y220225D02*
G03X1179647I984J0D01*
G01D02*
G03X1177679I-984J0D01*
G01X1160200Y224908D02*
G03X1162168I984J0D01*
G01D02*
G03X1160200I-984J0D01*
G01X1164883Y220225D02*
G03X1166852I984J0D01*
G01D02*
G03X1164883I-985J0D01*
G01X1182362Y237703D02*
G03X1184331I984J0D01*
G01D02*
G03X1182362I-984J0D01*
G01X1177679Y242386D02*
G03X1179647I984J0D01*
G01D02*
G03X1177679I-984J0D01*
G01X1160200Y237703D02*
G03X1162168I984J0D01*
G01D02*
G03X1160200I-984J0D01*
G01X1164883Y242386D02*
G03X1166852I984J0D01*
G01D02*
G03X1164883I-985J0D01*
G01X1162423Y231306D02*
G03X1182108I9843J0D01*
G01D02*
G03X1162423I-9842J0D01*
G01X1156517D02*
G03X1188013I15748J0D01*
G01D02*
G03X1156517I-15748J0D01*
G01X1182362Y224908D02*
G03X1184331I984J0D01*
G01D02*
G03X1182362I-984J0D01*
G01X1177679Y220225D02*
G03X1179647I984J0D01*
G01D02*
G03X1177679I-984J0D01*
G01X1160200Y224908D02*
G03X1162168I984J0D01*
G01D02*
G03X1160200I-984J0D01*
G01X1164883Y220225D02*
G03X1166852I984J0D01*
G01D02*
G03X1164883I-985J0D01*
G01X1182362Y237703D02*
G03X1184331I984J0D01*
G01D02*
G03X1182362I-984J0D01*
G01X1177679Y242386D02*
G03X1179647I984J0D01*
G01D02*
G03X1177679I-984J0D01*
G01X1160200Y237703D02*
G03X1162168I984J0D01*
G01D02*
G03X1160200I-984J0D01*
G01X1164883Y242386D02*
G03X1166852I984J0D01*
G01D02*
G03X1164883I-985J0D01*
G01X1180533Y231306D02*
G03X1163998I-8267J0D01*
G01D02*
G03X1180533I8268J0D01*
G01X1156517D02*
G03X1188013I15748J0D01*
G01D02*
G03X1156517I-15748J0D01*
G01X1163998D02*
G03X1180533I8268J0D01*
G01D02*
G03X1163998I-8267J0D01*
G01X1186045Y211621D02*
G03X1189982Y215558I0J3937D01*
G01D02*
Y269495D01*
G01D02*
G03X1186045Y273432I-3937J0D01*
G01X1163998Y231306D02*
G03X1180533I8268J0D01*
G01D02*
G03X1163998I-8267J0D01*
G01X1189982Y215558D02*
Y269495D01*
G01X1186045Y211621D02*
G03X1189982Y215558I0J3937D01*
G01Y269495D02*
G03X1186045Y273432I-3937J0D01*
G01X1112534Y304538D02*
Y313199D01*
G01X1118381Y305259D02*
X1118868Y304538D01*
G01X1118381D02*
Y305259D01*
G01X1118868Y304538D02*
X1118381D01*
G01X1124715D02*
X1128612D01*
G01X1125202Y306703D02*
X1124715Y304538D01*
G01X1126176Y308147D02*
X1125202Y306703D01*
G01X1127150Y308868D02*
X1126176Y308147D01*
G01X1128125Y309590D02*
X1127150Y308868D01*
G01X1128612Y310312D02*
X1128125Y309590D01*
G01X1128612Y311755D02*
Y310312D01*
G01X1128125Y312477D02*
X1128612Y311755D01*
G01X1127150Y313199D02*
X1128125Y312477D01*
G01X1126176Y313199D02*
X1127150D01*
G01X1125202Y312477D02*
X1126176Y313199D01*
G01X1124715Y311755D02*
X1125202Y312477D01*
G01X1135433Y305259D02*
X1134459Y304538D01*
G01X1135920Y305981D02*
X1135433Y305259D01*
G01X1136407Y307425D02*
X1135920Y305981D01*
G01X1136407Y310312D02*
Y307425D01*
G01X1135920Y311755D02*
X1136407Y310312D01*
G01X1135433Y312477D02*
X1135920Y311755D01*
G01X1134459Y313199D02*
X1135433Y312477D01*
G01X1133484D02*
X1134459Y313199D01*
G01X1132997Y311755D02*
X1133484Y312477D01*
G01X1132510Y310312D02*
X1132997Y311755D01*
G01X1132510Y307425D02*
Y310312D01*
G01X1132997Y305981D02*
X1132510Y307425D01*
G01X1133484Y305259D02*
X1132997Y305981D01*
G01X1134459Y304538D02*
X1133484Y305259D01*
G01X1150536Y308868D02*
X1148100D01*
G01X1151511Y309590D02*
X1150536Y308868D01*
G01X1151998Y310312D02*
X1151511Y309590D01*
G01X1151998Y311755D02*
Y310312D01*
G01X1151511Y312477D02*
X1151998Y311755D01*
G01X1150536Y313199D02*
X1151511Y312477D01*
G01X1148100Y313199D02*
X1150536D01*
G01X1148100Y304538D02*
Y313199D01*
G01X1163691Y308868D02*
X1167589D01*
G01Y313199D02*
Y304538D01*
G01X1163691Y313199D02*
Y304538D01*
G01X1157844Y313199D02*
Y304538D01*
G01X1155408Y313199D02*
X1160280D01*
G01X1185550Y445568D02*
X1239120D01*
G01X1114289Y379919D02*
X1110878D01*
G01X1113802Y381363D02*
X1114289Y379919D01*
G01X1112827Y382084D02*
X1113802Y381363D01*
G01X1111853D02*
X1112827Y382084D01*
G01X1110878Y379919D02*
X1111853Y381363D01*
G01X1110878Y378476D02*
Y379919D01*
G01X1111853Y377032D02*
X1110878Y378476D01*
G01X1112827Y376310D02*
X1111853Y377032D01*
G01X1113802D02*
X1112827Y376310D01*
G01X1114289Y377754D02*
X1113802Y377032D01*
G01X1122084Y380641D02*
Y376310D01*
G01X1121109Y382084D02*
X1122084Y380641D01*
G01X1120135Y382084D02*
X1121109D01*
G01X1119161Y380641D02*
X1120135Y382084D01*
G01X1143034Y377032D02*
X1142546Y377754D01*
G01X1143521Y376310D02*
X1143034Y377032D01*
G01X1144495Y376310D02*
X1143521D01*
G01X1144983Y377032D02*
X1144495Y376310D01*
G01X1145470Y377754D02*
X1144983Y377032D01*
G01X1145470Y378476D02*
Y377754D01*
G01X1144983Y379197D02*
X1145470Y378476D01*
G01X1144008Y379919D02*
X1144983Y379197D01*
G01X1143034Y380641D02*
X1144008Y379919D01*
G01X1143034Y381363D02*
Y380641D01*
G01X1143521Y382084D02*
X1143034Y381363D01*
G01X1144495Y382084D02*
X1143521D01*
G01X1144983Y381363D02*
X1144495Y382084D01*
G01X1160573Y381363D02*
X1161548Y379919D01*
G01X1159599Y382084D02*
X1160573Y381363D01*
G01X1158624D02*
X1159599Y382084D01*
G01X1157650Y379919D02*
X1158624Y381363D01*
G01X1157650Y378476D02*
Y379919D01*
G01X1158624Y377032D02*
X1157650Y378476D01*
G01X1159599Y376310D02*
X1158624Y377032D01*
G01X1160573D02*
X1159599Y376310D01*
G01X1161548Y378476D02*
X1160573Y377032D01*
G01X1168855Y379919D02*
X1165445D01*
G01X1168368Y381363D02*
X1168855Y379919D01*
G01X1167394Y382084D02*
X1168368Y381363D01*
G01X1166420D02*
X1167394Y382084D01*
G01X1165445Y379919D02*
X1166420Y381363D01*
G01X1165445Y378476D02*
Y379919D01*
G01X1166420Y377032D02*
X1165445Y378476D01*
G01X1167394Y376310D02*
X1166420Y377032D01*
G01X1168368D02*
X1167394Y376310D01*
G01X1168855Y377754D02*
X1168368Y377032D01*
G01X1161548Y384972D02*
Y376310D01*
G01X1151803Y382084D02*
Y376310D01*
G01Y384972D02*
Y384250D01*
G01X1126956Y381363D02*
X1129879D01*
G01X1128418Y376310D02*
Y384972D01*
G01X1119161Y376310D02*
Y382084D01*
G01X1181613Y445568D02*
G03X1185550Y449505I0J3937D01*
G01X1181613Y445568D02*
G03X1185550Y449505I0J3937D01*
G01X1181613Y445568D02*
G03X1185550Y449505I0J3937D01*
G01X1115169Y492716D02*
X1114801Y493279D01*
G01X1115353Y494218D02*
X1116088Y493467D01*
G01X1114801Y493279D02*
X1114250Y493655D01*
G01X1114618Y494593D02*
X1115353Y494218D01*
G01X1114250Y493655D02*
X1113332Y493842D01*
G01X1113515Y494781D02*
X1114618Y494593D01*
G01X1112780Y494781D02*
X1113515D01*
G01X1113332Y493842D02*
X1112597D01*
G01X1111494Y494593D02*
X1112780Y494781D01*
G01X1112597Y493842D02*
X1111678Y493655D01*
G01X1115169Y492341D02*
Y492716D01*
G01X1111127Y486900D02*
X1116271D01*
G01X1116088Y491591D02*
X1115720Y491028D01*
G01X1114801Y491591D02*
X1115169Y492341D01*
G01X1115720Y491028D02*
X1111127Y486900D01*
G01Y493279D02*
X1110760Y492716D01*
G01X1110025Y493467D02*
X1110760Y494218D01*
G01D02*
X1111494Y494593D01*
G01X1111678Y493655D02*
X1111127Y493279D01*
G01X1140523Y491403D02*
X1140891Y490465D01*
G01X1139972D02*
X1139788Y490840D01*
G01X1137032Y490465D02*
X1136849Y490840D01*
G01X1140156Y491778D02*
X1140523Y491403D01*
G01X1139788Y490840D02*
X1139604Y491028D01*
G01X1137216Y491778D02*
X1137767Y491216D01*
G01X1136849Y490840D02*
X1136665Y491028D01*
G01X1140891Y490465D02*
Y485962D01*
G01X1139972D02*
Y490465D01*
G01X1137951D02*
Y485962D01*
G01X1137032D02*
Y490465D01*
G01X1132256Y491403D02*
X1132623Y490465D01*
G01X1131704D02*
X1131521Y490840D01*
G01X1128765Y490465D02*
X1128581Y490840D01*
G01X1131888Y491778D02*
X1132256Y491403D01*
G01X1131521Y490840D02*
X1131337Y491028D01*
G01X1128949Y491778D02*
X1129500Y491216D01*
G01X1128581Y490840D02*
X1128397Y491028D01*
G01X1139604D02*
X1139237Y491216D01*
G01X1135012Y490653D02*
Y485962D01*
G01Y491966D02*
Y491403D01*
G01X1134093Y485962D02*
Y491966D01*
G01X1132623Y490465D02*
Y485962D01*
G01X1131704D02*
Y490465D01*
G01X1129683D02*
Y485962D01*
G01X1123253Y489527D02*
X1123437Y488964D01*
G01X1124355Y489151D02*
X1123988Y490090D01*
G01X1122886D02*
X1123253Y489527D01*
G01X1123988Y490090D02*
X1123437Y490840D01*
G01D02*
X1122518Y491403D01*
G01X1136665Y491028D02*
X1136297Y491216D01*
G01X1131337Y491028D02*
X1130969Y491216D01*
G01X1128397Y491028D02*
X1128030Y491216D01*
G01X1139604Y491966D02*
X1140156Y491778D01*
G01X1136665Y491966D02*
X1137216Y491778D01*
G01X1138135Y490840D02*
X1137951Y490465D01*
G01X1128765Y485962D02*
Y490465D01*
G01X1126744Y490653D02*
Y485962D01*
G01Y491966D02*
Y491403D01*
G01X1125825Y485962D02*
Y491966D01*
G01X1124355Y488401D02*
Y489151D01*
G01X1123988Y493842D02*
Y494781D01*
G01X1123437Y488964D02*
Y488588D01*
G01X1116088Y493467D02*
X1116271Y492716D01*
G01X1119211Y487463D02*
X1118843Y488213D01*
G01X1117741D02*
X1118108Y487463D01*
G01D02*
X1118660Y486712D01*
G01X1122334Y490465D02*
X1122886Y490090D01*
G01X1119762Y487087D02*
X1119211Y487463D01*
G01X1118660Y486712D02*
X1119578Y486149D01*
G01X1131337Y491966D02*
X1131888Y491778D01*
G01X1128397Y491966D02*
X1128949Y491778D01*
G01X1121599Y490653D02*
X1122334Y490465D01*
G01X1122518Y491403D02*
X1121599Y491591D01*
G01X1129867Y490840D02*
X1129683Y490465D01*
G01X1123988Y487463D02*
X1124355Y488401D01*
G01X1123437Y488588D02*
X1123253Y488025D01*
G01X1118660Y490840D02*
Y493842D01*
G01X1117741Y494781D02*
Y489902D01*
G01X1120497Y486900D02*
X1119762Y487087D01*
G01X1119578Y486149D02*
X1120497Y485962D01*
G01X1123988Y494781D02*
X1117741D01*
G01X1118660Y493842D02*
X1123988D01*
G01X1138870Y491966D02*
X1139604D01*
G01X1135930D02*
X1136665D01*
G01X1134093D02*
X1135012D01*
G01X1130602D02*
X1131337D01*
G01X1127662D02*
X1128397D01*
G01X1125825D02*
X1126744D01*
G01X1121599Y491591D02*
X1120497D01*
G01X1128030Y491216D02*
X1127662D01*
G01X1130969D02*
X1130418D01*
G01X1136297D02*
X1135930D01*
G01X1139237D02*
X1138686D01*
G01X1120497Y490653D02*
X1121599D01*
G01X1117741Y489902D02*
X1119027D01*
G01X1138319Y491028D02*
X1138135Y490840D01*
G01X1137767Y491216D02*
X1138319Y491778D01*
G01X1135379Y491028D02*
X1135012Y490653D01*
G01Y491403D02*
X1135379Y491778D01*
G01X1130051Y491028D02*
X1129867Y490840D01*
G01X1123437Y486712D02*
X1123988Y487463D01*
G01X1123253Y488025D02*
X1122886Y487463D01*
G01X1116271Y492341D02*
X1116088Y491591D01*
G01X1116271Y486900D02*
Y485962D01*
G01Y492716D02*
Y492341D01*
G01X1118843Y488213D02*
X1117741D01*
G01X1121599Y486900D02*
X1120497D01*
G01Y485962D02*
X1121599D01*
G01X1126744D02*
X1125825D01*
G01X1129683D02*
X1128765D01*
G01X1132623D02*
X1131704D01*
G01X1135012D02*
X1134093D01*
G01X1137951D02*
X1137032D01*
G01X1140891D02*
X1139972D01*
G01X1120497Y491591D02*
X1119578Y491403D01*
G01X1119762Y490465D02*
X1120497Y490653D01*
G01X1129500Y491216D02*
X1130051Y491778D01*
G01X1127111Y491028D02*
X1126744Y490653D01*
G01Y491403D02*
X1127111Y491778D01*
G01X1121599Y485962D02*
X1122518Y486149D01*
G01X1122334Y487087D02*
X1121599Y486900D01*
G01X1138686Y491216D02*
X1138319Y491028D01*
G01X1130418Y491216D02*
X1130051Y491028D01*
G01X1122518Y486149D02*
X1123437Y486712D01*
G01X1122886Y487463D02*
X1122334Y487087D01*
G01X1119027Y489902D02*
X1119762Y490465D01*
G01X1138319Y491778D02*
X1138870Y491966D01*
G01X1135930Y491216D02*
X1135379Y491028D01*
G01Y491778D02*
X1135930Y491966D01*
G01X1130051Y491778D02*
X1130602Y491966D01*
G01X1127662Y491216D02*
X1127111Y491028D01*
G01Y491778D02*
X1127662Y491966D01*
G01X1119578Y491403D02*
X1118660Y490840D01*
G01X1185550Y507379D02*
X1239120D01*
G01X1185550D02*
Y527863D01*
G01X1125313Y450982D02*
Y451277D01*
G01D02*
X1127676D01*
G01D02*
Y450982D01*
G01D02*
X1126520D01*
G01D02*
X1127676Y449899D01*
G01D02*
Y449505D01*
G01D02*
X1126720Y450391D01*
G01D02*
X1125313Y449505D01*
G01D02*
Y449899D01*
G01D02*
X1126469Y450637D01*
G01D02*
X1126117Y450982D01*
G01D02*
X1125313D01*
G01X1126117Y460775D02*
X1127474Y460332D01*
G01X1126117Y459889D02*
Y460775D01*
G01X1127474Y460332D02*
X1126117Y459889D01*
G01X1127676Y460135D02*
X1125313Y459348D01*
G01D02*
Y459643D01*
G01D02*
X1125916Y459840D01*
G01D02*
Y460824D01*
G01D02*
X1125313Y461021D01*
G01D02*
Y461316D01*
G01D02*
X1127676Y460529D01*
G01D02*
Y460135D01*
G01X1111140Y450982D02*
Y451277D01*
G01D02*
X1113502D01*
G01D02*
Y450982D01*
G01D02*
X1112346D01*
G01D02*
X1113502Y449899D01*
G01D02*
Y449505D01*
G01D02*
X1112547Y450391D01*
G01D02*
X1111140Y449505D01*
G01D02*
Y449899D01*
G01D02*
X1112296Y450637D01*
G01D02*
X1111944Y450982D01*
G01D02*
X1111140D01*
G01X1111944Y460775D02*
X1113301Y460332D01*
G01X1111944Y459889D02*
Y460775D01*
G01X1113301Y460332D02*
X1111944Y459889D01*
G01X1113502Y460135D02*
X1111140Y459348D01*
G01D02*
Y459643D01*
G01D02*
X1111743Y459840D01*
G01D02*
Y460824D01*
G01D02*
X1111140Y461021D01*
G01D02*
Y461316D01*
G01D02*
X1113502Y460529D01*
G01D02*
Y460135D01*
G01X1172464Y474269D02*
X1172083D01*
G01D02*
Y476762D01*
G01D02*
X1172464D01*
G01D02*
Y476528D01*
G01D02*
X1172616Y476684D01*
G01D02*
X1172845Y476762D01*
G01D02*
X1173150D01*
G01D02*
X1173379Y476684D01*
G01D02*
X1173608Y476450D01*
G01D02*
X1173837Y476684D01*
G01D02*
X1174066Y476762D01*
G01D02*
X1174371D01*
G01D02*
X1174600Y476684D01*
G01D02*
X1174752Y476528D01*
G01D02*
X1174905Y476139D01*
G01D02*
Y474269D01*
G01D02*
X1174524D01*
G01D02*
Y476139D01*
G01D02*
X1174447Y476294D01*
G01D02*
X1174371Y476372D01*
G01D02*
X1174218Y476450D01*
G01D02*
X1173989D01*
G01D02*
X1173837Y476372D01*
G01D02*
X1173761Y476294D01*
G01D02*
X1173684Y476139D01*
G01D02*
Y474269D01*
G01D02*
X1173303D01*
G01D02*
Y476139D01*
G01D02*
X1173227Y476294D01*
G01D02*
X1173150Y476372D01*
G01D02*
X1172998Y476450D01*
G01D02*
X1172845D01*
G01D02*
X1172616Y476372D01*
G01D02*
X1172464Y476216D01*
G01D02*
Y474269D01*
G01X1169031D02*
X1168650D01*
G01D02*
Y476762D01*
G01D02*
X1169031D01*
G01D02*
Y476528D01*
G01D02*
X1169184Y476684D01*
G01D02*
X1169413Y476762D01*
G01D02*
X1169718D01*
G01D02*
X1169947Y476684D01*
G01D02*
X1170176Y476450D01*
G01D02*
X1170404Y476684D01*
G01D02*
X1170633Y476762D01*
G01D02*
X1170938D01*
G01D02*
X1171167Y476684D01*
G01D02*
X1171320Y476528D01*
G01D02*
X1171472Y476139D01*
G01D02*
Y474269D01*
G01D02*
X1171091D01*
G01D02*
Y476139D01*
G01D02*
X1171015Y476294D01*
G01D02*
X1170938Y476372D01*
G01D02*
X1170786Y476450D01*
G01D02*
X1170557D01*
G01D02*
X1170404Y476372D01*
G01D02*
X1170328Y476294D01*
G01D02*
X1170252Y476139D01*
G01D02*
Y474269D01*
G01D02*
X1169870D01*
G01D02*
Y476139D01*
G01D02*
X1169794Y476294D01*
G01D02*
X1169718Y476372D01*
G01D02*
X1169565Y476450D01*
G01D02*
X1169413D01*
G01D02*
X1169184Y476372D01*
G01D02*
X1169031Y476216D01*
G01D02*
Y474269D01*
G01X1165675Y476372D02*
Y475827D01*
G01D02*
X1165751Y475360D01*
G01D02*
X1166056Y474892D01*
G01D02*
X1166285Y474736D01*
G01D02*
X1166666Y474658D01*
G01D02*
X1167048Y474736D01*
G01D02*
X1167277Y474892D01*
G01D02*
X1167582Y475360D01*
G01D02*
X1167658Y475827D01*
G01D02*
Y476372D01*
G01D02*
X1167582Y476840D01*
G01D02*
X1167277Y477307D01*
G01D02*
X1167048Y477463D01*
G01D02*
X1166666Y477541D01*
G01D02*
X1166285Y477463D01*
G01D02*
X1166056Y477307D01*
G01D02*
X1165751Y476840D01*
G01D02*
X1165675Y476372D01*
G01X1165370Y476840D02*
X1165294Y476450D01*
G01X1165446Y477073D02*
X1165370Y476840D01*
G01X1165599Y477385D02*
X1165446Y477073D01*
G01X1165828Y477619D02*
X1165599Y477385D01*
G01X1166209Y477853D02*
X1165828Y477619D01*
G01X1166666Y477930D02*
X1166209Y477853D01*
G01X1167124D02*
X1166666Y477930D01*
G01X1167506Y477619D02*
X1167124Y477853D01*
G01X1167735Y477385D02*
X1167506Y477619D01*
G01X1167887Y477073D02*
X1167735Y477385D01*
G01X1167963Y476840D02*
X1167887Y477073D01*
G01X1168040Y476450D02*
X1167963Y476840D01*
G01X1168040Y475749D02*
Y476450D01*
G01X1167963Y475360D02*
X1168040Y475749D01*
G01X1167887Y475126D02*
X1167963Y475360D01*
G01X1167735Y474814D02*
X1167887Y475126D01*
G01X1167506Y474580D02*
X1167735Y474814D01*
G01X1167124Y474347D02*
X1167506Y474580D01*
G01X1166666Y474269D02*
X1167124Y474347D01*
G01X1166209D02*
X1166666Y474269D01*
G01X1165828Y474580D02*
X1166209Y474347D01*
G01X1165599Y474814D02*
X1165828Y474580D01*
G01X1165446Y475126D02*
X1165599Y474814D01*
G01X1165370Y475360D02*
X1165446Y475126D01*
G01X1165294Y475749D02*
X1165370Y475360D01*
G01X1165294Y476450D02*
Y475749D01*
G01X1163463Y475827D02*
X1164683D01*
G01D02*
Y475516D01*
G01D02*
X1163463D01*
G01D02*
Y475827D01*
G01Y476762D02*
X1164683D01*
G01D02*
Y476450D01*
G01D02*
X1163463D01*
G01D02*
Y476762D01*
G01X1160259Y474269D02*
X1159802D01*
G01D02*
Y477930D01*
G01D02*
X1160259D01*
G01D02*
Y476450D01*
G01D02*
X1162395D01*
G01D02*
Y477930D01*
G01D02*
X1162853D01*
G01D02*
Y474269D01*
G01D02*
X1162395D01*
G01D02*
Y475983D01*
G01D02*
X1160259D01*
G01D02*
Y474269D01*
G01X1152085Y465253D02*
G03X1183581I15748J0D01*
G01D02*
G03X1152085I-15748J0D01*
G01X1185550Y503442D02*
G03X1181613Y507379I-3937J0D01*
G01X1185550Y449505D02*
Y503442D01*
G01X1126494Y452621D02*
G03Y458201I0J2790D01*
G01D02*
G03Y452621I0J-2790D01*
G01Y456240D02*
G03Y454582I0J-829D01*
G01D02*
G03Y456240I0J829D01*
G01X1123345Y455411D02*
Y449112D01*
G01D02*
X1129644D01*
G01D02*
Y455411D01*
G01X1126494Y452261D02*
G03X1129644Y455411I0J3150D01*
G01X1123345D02*
G03X1126494Y452261I3150J0D01*
G01X1129644Y455411D02*
G03X1126494Y458560I-3149J0D01*
G01X1129644Y455411D02*
Y461710D01*
G01D02*
X1123345D01*
G01D02*
Y455411D01*
G01X1126494Y458560D02*
G03X1123345Y455411I0J-3149D01*
G01X1129644Y449112D02*
Y461710D01*
G01X1123345Y449112D02*
X1129644D01*
G01X1123345Y461710D02*
Y449112D01*
G01X1129644Y461710D02*
X1123345D01*
G01X1112321Y452621D02*
G03Y458201I0J2790D01*
G01Y456240D02*
G03Y454582I0J-829D01*
G01D02*
G03Y456240I0J829D01*
G01X1115471Y449112D02*
Y455411D01*
G01X1112321Y452261D02*
G03X1115471Y455411I0J3150D01*
G01D02*
G03X1112321Y458560I-3150J-1D01*
G01X1115471Y455411D02*
Y461710D01*
G01Y449112D02*
Y461710D01*
G01X1183457Y463285D02*
X1177477D01*
G01X1169802Y455610D02*
G03X1177477Y463285I-1969J9644D01*
G01X1169802Y455610D02*
Y449629D01*
G01X1165865D02*
Y455610D01*
G01X1158189Y463285D02*
G03X1165865Y455610I9644J1969D01*
G01X1158189Y463285D02*
X1152209D01*
G01Y467222D02*
X1158189D01*
G01X1165865Y474897D02*
G03X1158189Y467222I1968J-9644D01*
G01X1165865Y474897D02*
Y480878D01*
G01X1169802D02*
Y474897D01*
G01X1177477Y467222D02*
G03X1169802Y474897I-9644J-1969D01*
G01X1177477Y467222D02*
X1183457D01*
G01X1157991Y465253D02*
G03X1177676I9842J0D01*
G01D02*
G03X1157991I-9843J0D01*
G01X1165865Y449629D02*
G03X1169802I1968J15624D01*
G01X1183457Y463285D02*
G03X1183581Y465253I-15624J1972D01*
G01X1152085D02*
G03X1152209Y463285I15748J4D01*
G01X1169802Y480878D02*
G03X1165865I-1969J-15625D01*
G01X1152209Y467222D02*
G03X1152085Y465253I15624J-1972D01*
G01X1183581D02*
G03X1183457Y467222I-15748J-3D01*
G01X1176101Y465253D02*
G03X1159565I-8268J0D01*
G01D02*
G03X1176101I8268J0D01*
G01X1169802Y455610D02*
G03X1177477Y463285I-1969J9644D01*
G01X1183457D02*
X1177477D01*
G01X1169802Y449629D02*
G03X1183457Y463285I-1969J15624D01*
G01X1169802Y455610D02*
Y449629D01*
G01X1158189Y463285D02*
G03X1165865Y455610I9644J1969D01*
G01Y449629D02*
Y455610D01*
G01X1152209Y463285D02*
G03X1165865Y449629I15624J1968D01*
G01X1158189Y463285D02*
X1152209D01*
G01X1165865Y474897D02*
G03X1158189Y467222I1968J-9644D01*
G01X1152209D02*
X1158189D01*
G01X1165865Y480878D02*
G03X1152209Y467222I1968J-15624D01*
G01X1165865Y474897D02*
Y480878D01*
G01X1183457Y467222D02*
G03X1169802Y480878I-15624J-1968D01*
G01X1177477Y467222D02*
X1183457D01*
G01X1177477D02*
G03X1169802Y474897I-9644J-1969D01*
G01Y480878D02*
Y474897D01*
G01X1177930Y458856D02*
G03X1179898I984J0D01*
G01D02*
G03X1177930I-984J0D01*
G01X1173246Y454172D02*
G03X1175215I985J0D01*
G01D02*
G03X1173246I-985J0D01*
G01X1155768Y458856D02*
G03X1157736I984J0D01*
G01D02*
G03X1155768I-984J0D01*
G01X1160451Y454172D02*
G03X1162420I984J0D01*
G01D02*
G03X1160451I-985J0D01*
G01X1177930Y471651D02*
G03X1179898I984J0D01*
G01D02*
G03X1177930I-984J0D01*
G01X1173246Y476334D02*
G03X1175215I985J0D01*
G01D02*
G03X1173246I-985J0D01*
G01X1155768Y471651D02*
G03X1157736I984J0D01*
G01D02*
G03X1155768I-984J0D01*
G01X1160451Y476334D02*
G03X1162420I984J0D01*
G01D02*
G03X1160451I-985J0D01*
G01X1177930Y458856D02*
G03X1179898I984J0D01*
G01D02*
G03X1177930I-984J0D01*
G01X1173246Y454172D02*
G03X1175215I985J0D01*
G01D02*
G03X1173246I-985J0D01*
G01X1155768Y458856D02*
G03X1157736I984J0D01*
G01D02*
G03X1155768I-984J0D01*
G01X1160451Y454172D02*
G03X1162420I984J0D01*
G01D02*
G03X1160451I-985J0D01*
G01X1177930Y471651D02*
G03X1179898I984J0D01*
G01D02*
G03X1177930I-984J0D01*
G01X1173246Y476334D02*
G03X1175215I985J0D01*
G01D02*
G03X1173246I-985J0D01*
G01X1155768Y471651D02*
G03X1157736I984J0D01*
G01D02*
G03X1155768I-984J0D01*
G01X1160451Y476334D02*
G03X1162420I984J0D01*
G01D02*
G03X1160451I-985J0D01*
G01X1152085Y465253D02*
G03X1183581I15748J0D01*
G01D02*
G03X1152085I-15748J0D01*
G01X1176101D02*
G03X1159565I-8268J0D01*
G01D02*
G03X1176101I8268J0D01*
G01D02*
G03X1159565I-8268J0D01*
G01D02*
G03X1176101I8268J0D01*
G01X1177930Y458856D02*
G03X1179898I984J0D01*
G01D02*
G03X1177930I-984J0D01*
G01X1173246Y454172D02*
G03X1175215I985J0D01*
G01D02*
G03X1173246I-985J0D01*
G01X1155768Y458856D02*
G03X1157736I984J0D01*
G01D02*
G03X1155768I-984J0D01*
G01X1160451Y454172D02*
G03X1162420I984J0D01*
G01D02*
G03X1160451I-985J0D01*
G01X1177930Y471651D02*
G03X1179898I984J0D01*
G01D02*
G03X1177930I-984J0D01*
G01X1173246Y476334D02*
G03X1175215I985J0D01*
G01D02*
G03X1173246I-985J0D01*
G01X1155768Y471651D02*
G03X1157736I984J0D01*
G01D02*
G03X1155768I-984J0D01*
G01X1160451Y476334D02*
G03X1162420I984J0D01*
G01D02*
G03X1160451I-985J0D01*
G01X1157991Y465253D02*
G03X1177676I9842J0D01*
G01D02*
G03X1157991I-9843J0D01*
G01X1152085D02*
G03X1183581I15748J0D01*
G01D02*
G03X1152085I-15748J0D01*
G01X1177930Y458856D02*
G03X1179898I984J0D01*
G01D02*
G03X1177930I-984J0D01*
G01X1173246Y454172D02*
G03X1175215I985J0D01*
G01D02*
G03X1173246I-985J0D01*
G01X1155768Y458856D02*
G03X1157736I984J0D01*
G01D02*
G03X1155768I-984J0D01*
G01X1160451Y454172D02*
G03X1162420I984J0D01*
G01D02*
G03X1160451I-985J0D01*
G01X1177930Y471651D02*
G03X1179898I984J0D01*
G01D02*
G03X1177930I-984J0D01*
G01X1173246Y476334D02*
G03X1175215I985J0D01*
G01D02*
G03X1173246I-985J0D01*
G01X1155768Y471651D02*
G03X1157736I984J0D01*
G01D02*
G03X1155768I-984J0D01*
G01X1160451Y476334D02*
G03X1162420I984J0D01*
G01D02*
G03X1160451I-985J0D01*
G01X1176101Y465253D02*
G03X1159565I-8268J0D01*
G01D02*
G03X1176101I8268J0D01*
G01X1152085D02*
G03X1183581I15748J0D01*
G01D02*
G03X1152085I-15748J0D01*
G01X1159565D02*
G03X1176101I8268J0D01*
G01D02*
G03X1159565I-8268J0D01*
G01X1185550Y449505D02*
Y503442D01*
G01D02*
G03X1181613Y507379I-3937J0D01*
G01X1159565Y465253D02*
G03X1176101I8268J0D01*
G01D02*
G03X1159565I-8268J0D01*
G01X1185550Y449505D02*
Y503442D01*
G01D02*
G03X1181613Y507379I-3937J0D01*
G01X1181219Y534142D02*
Y538527D01*
G01X1174723Y537553D02*
X1181219Y534142D01*
G01X1183384Y537553D02*
X1174723D01*
G01X1182663Y542425D02*
X1181941Y541938D01*
G01X1183384Y543399D02*
X1182663Y542425D01*
G01X1183384Y544373D02*
Y543399D01*
G01X1182663Y545348D02*
X1183384Y544373D01*
G01X1181941Y545835D02*
X1182663Y545348D01*
G01X1180497Y546322D02*
X1181941Y545835D01*
G01X1179053D02*
X1180497Y546322D01*
G01X1178332Y545348D02*
X1179053Y545835D01*
G01X1177610Y544373D02*
X1178332Y545348D01*
G01X1177610Y543399D02*
Y544373D01*
G01X1178332Y542425D02*
X1177610Y543399D01*
G01X1174723Y542912D02*
X1178332Y542425D01*
G01X1174723Y545835D02*
Y542912D01*
G01X1182663Y551194D02*
X1183384Y551682D01*
G01Y551194D02*
X1182663D01*
G01X1183384Y551682D02*
Y551194D01*
G01X1182663Y560451D02*
X1183384Y559477D01*
G01X1181941Y560938D02*
X1182663Y560451D01*
G01X1180497Y561426D02*
X1181941Y560938D01*
G01X1177610Y561426D02*
X1180497D01*
G01X1176166Y560938D02*
X1177610Y561426D01*
G01X1175444Y560451D02*
X1176166Y560938D01*
G01X1174723Y559477D02*
X1175444Y560451D01*
G01Y558503D02*
X1174723Y559477D01*
G01X1176166Y558015D02*
X1175444Y558503D01*
G01X1177610Y557528D02*
X1176166Y558015D01*
G01X1180497Y557528D02*
X1177610D01*
G01X1181941Y558015D02*
X1180497Y557528D01*
G01X1182663Y558503D02*
X1181941Y558015D01*
G01X1183384Y559477D02*
X1182663Y558503D01*
G01Y568247D02*
X1183384Y567272D01*
G01X1181941Y568734D02*
X1182663Y568247D01*
G01X1180497Y569221D02*
X1181941Y568734D01*
G01X1177610Y569221D02*
X1180497D01*
G01X1176166Y568734D02*
X1177610Y569221D01*
G01X1175444Y568247D02*
X1176166Y568734D01*
G01X1174723Y567272D02*
X1175444Y568247D01*
G01Y566298D02*
X1174723Y567272D01*
G01X1176166Y565810D02*
X1175444Y566298D01*
G01X1177610Y565323D02*
X1176166Y565810D01*
G01X1180497Y565323D02*
X1177610D01*
G01X1181941Y565810D02*
X1180497Y565323D01*
G01X1182663Y566298D02*
X1181941Y565810D01*
G01X1183384Y567272D02*
X1182663Y566298D01*
G01X1164178Y978747D02*
Y961424D01*
G01X1253682Y510266D02*
X1253194Y510988D01*
G01X1254656Y509545D02*
X1253682Y510266D01*
G01X1255631Y509545D02*
X1254656D01*
G01X1256605Y510266D02*
X1255631Y509545D01*
G01X1257092Y510988D02*
X1256605Y510266D01*
G01X1257579Y512432D02*
X1257092Y510988D01*
G01Y513875D02*
X1257579Y512432D01*
G01X1256605Y514597D02*
X1257092Y513875D01*
G01X1255631Y515319D02*
X1256605Y514597D01*
G01X1254656Y515319D02*
X1255631D01*
G01X1253682Y514597D02*
X1254656Y515319D01*
G01X1254169Y518206D02*
X1253682Y514597D01*
G01X1257092Y518206D02*
X1254169D01*
G01X1262452Y510266D02*
X1262939Y509545D01*
G01X1262452D02*
Y510266D01*
G01X1262939Y509545D02*
X1262452D01*
G01X1272683Y518206D02*
X1268785D01*
G01X1272196Y516762D02*
X1272683Y518206D01*
G01X1271708Y515319D02*
X1272196Y516762D01*
G01X1271221Y513153D02*
X1271708Y515319D01*
G01X1270734Y509545D02*
X1271221Y513153D01*
G01X1248322Y448455D02*
X1247348Y447734D01*
G01X1248810Y449177D02*
X1248322Y448455D01*
G01X1249297Y450621D02*
X1248810Y449177D01*
G01X1249297Y453508D02*
Y450621D01*
G01X1248810Y454951D02*
X1249297Y453508D01*
G01X1248322Y455673D02*
X1248810Y454951D01*
G01X1247348Y456395D02*
X1248322Y455673D01*
G01X1246374D02*
X1247348Y456395D01*
G01X1245887Y454951D02*
X1246374Y455673D01*
G01X1245399Y453508D02*
X1245887Y454951D01*
G01X1245399Y450621D02*
Y453508D01*
G01X1245887Y449177D02*
X1245399Y450621D01*
G01X1246374Y448455D02*
X1245887Y449177D01*
G01X1247348Y447734D02*
X1246374Y448455D01*
G01X1254656D02*
X1255143Y447734D01*
G01X1254656D02*
Y448455D01*
G01X1255143Y447734D02*
X1254656D01*
G01X1263913Y448455D02*
X1262939Y447734D01*
G01X1264400Y449177D02*
X1263913Y448455D01*
G01X1264887Y450621D02*
X1264400Y449177D01*
G01X1264887Y453508D02*
Y450621D01*
G01X1264400Y454951D02*
X1264887Y453508D01*
G01X1263913Y455673D02*
X1264400Y454951D01*
G01X1262939Y456395D02*
X1263913Y455673D01*
G01X1261964D02*
X1262939Y456395D01*
G01X1261477Y454951D02*
X1261964Y455673D01*
G01X1260990Y453508D02*
X1261477Y454951D01*
G01X1260990Y450621D02*
Y453508D01*
G01X1261477Y449177D02*
X1260990Y450621D01*
G01X1261964Y448455D02*
X1261477Y449177D01*
G01X1262939Y447734D02*
X1261964Y448455D01*
G01X1271708D02*
X1270734Y447734D01*
G01X1272196Y449177D02*
X1271708Y448455D01*
G01X1272683Y450621D02*
X1272196Y449177D01*
G01X1272683Y453508D02*
Y450621D01*
G01X1272196Y454951D02*
X1272683Y453508D01*
G01X1271708Y455673D02*
X1272196Y454951D01*
G01X1270734Y456395D02*
X1271708Y455673D01*
G01X1269759D02*
X1270734Y456395D01*
G01X1269272Y454951D02*
X1269759Y455673D01*
G01X1268785Y453508D02*
X1269272Y454951D01*
G01X1268785Y450621D02*
Y453508D01*
G01X1269272Y449177D02*
X1268785Y450621D01*
G01X1269759Y448455D02*
X1269272Y449177D01*
G01X1270734Y447734D02*
X1269759Y448455D01*
G01X1247348Y518206D02*
Y509545D01*
G01X1337406Y-381883D02*
Y-399206D01*
G01X1296461Y-215427D02*
Y-305557D01*
G01X1300129Y-260745D02*
X1713784D01*
G01X1279503Y510266D02*
X1278529Y509545D01*
G01X1279991Y510988D02*
X1279503Y510266D01*
G01X1280478Y512432D02*
X1279991Y510988D01*
G01X1280478Y515319D02*
Y512432D01*
G01X1279991Y516762D02*
X1280478Y515319D01*
G01X1279503Y517484D02*
X1279991Y516762D01*
G01X1278529Y518206D02*
X1279503Y517484D01*
G01X1277555D02*
X1278529Y518206D01*
G01X1277068Y516762D02*
X1277555Y517484D01*
G01X1276580Y515319D02*
X1277068Y516762D01*
G01X1276580Y512432D02*
Y515319D01*
G01X1277068Y510988D02*
X1276580Y512432D01*
G01X1277555Y510266D02*
X1277068Y510988D01*
G01X1278529Y509545D02*
X1277555Y510266D01*
G01X1337406Y978747D02*
Y961424D01*
G01X1510635Y-381883D02*
Y-399206D01*
G01X1485438Y-215427D02*
Y-305557D01*
G01X1510635Y978747D02*
Y961424D01*
G01X1746854Y978747D02*
Y-399206D01*
G01X1713784Y-366135D02*
Y-110350D01*
G01X1729532Y961424D02*
Y-381883D01*
G01Y-202356D02*
X1746854D01*
G01X1729532Y33865D02*
X1746854D01*
G01X1729532Y270085D02*
X1746854D01*
G01X1729532Y506306D02*
X1746854D01*
G01X1729532Y742526D02*
X1746854D01*
M02*
